(kicad_sch
	(version 20250114)
	(generator "eeschema")
	(generator_version "9.0")
	(paper "A3")
	(title_block
		(title "Artix - Datacenter Secure Control Module (DC-SCM)")
		(date "2024-11-06")
		(rev "1.1.3")
	)
	(text "This bank is unavailable on 35T"
		(exclude_from_sim no)
		(at 56.515 151.765 90)
		(effects
			(font
				(size 1.27 1.27)
			)
			(justify left bottom)
		)
	)
	(junction
		(at 227.33 50.8)
		(diameter 0)
		(color 0 0 0 0)
	)
	(junction
		(at 137.16 63.5)
		(diameter 0)
		(color 0 0 0 0)
	)
	(junction
		(at 121.92 63.5)
		(diameter 0)
		(color 0 0 0 0)
	)
	(junction
		(at 245.11 64.77)
		(diameter 0)
		(color 0 0 0 0)
	)
	(junction
		(at 124.46 77.47)
		(diameter 0)
		(color 0 0 0 0)
	)
	(junction
		(at 50.8 50.8)
		(diameter 0)
		(color 0 0 0 0)
	)
	(junction
		(at 121.92 77.47)
		(diameter 0)
		(color 0 0 0 0)
	)
	(junction
		(at 341.63 49.53)
		(diameter 0)
		(color 0 0 0 0)
	)
	(junction
		(at 350.52 49.53)
		(diameter 0)
		(color 0 0 0 0)
	)
	(junction
		(at 138.43 99.06)
		(diameter 0)
		(color 0 0 0 0)
	)
	(junction
		(at 218.44 50.8)
		(diameter 0)
		(color 0 0 0 0)
	)
	(junction
		(at 359.41 49.53)
		(diameter 0)
		(color 0 0 0 0)
	)
	(junction
		(at 236.22 50.8)
		(diameter 0)
		(color 0 0 0 0)
	)
	(junction
		(at 137.16 49.53)
		(diameter 0)
		(color 0 0 0 0)
	)
	(junction
		(at 332.74 49.53)
		(diameter 0)
		(color 0 0 0 0)
	)
	(junction
		(at 132.08 96.52)
		(diameter 0)
		(color 0 0 0 0)
	)
	(junction
		(at 251.46 64.77)
		(diameter 0)
		(color 0 0 0 0)
	)
	(junction
		(at 124.46 116.84)
		(diameter 0)
		(color 0 0 0 0)
	)
	(junction
		(at 227.33 64.77)
		(diameter 0)
		(color 0 0 0 0)
	)
	(junction
		(at 365.76 152.4)
		(diameter 0)
		(color 0 0 0 0)
	)
	(junction
		(at 154.94 49.53)
		(diameter 0)
		(color 0 0 0 0)
	)
	(junction
		(at 128.27 63.5)
		(diameter 0)
		(color 0 0 0 0)
	)
	(junction
		(at 332.74 63.5)
		(diameter 0)
		(color 0 0 0 0)
	)
	(junction
		(at 350.52 63.5)
		(diameter 0)
		(color 0 0 0 0)
	)
	(junction
		(at 236.22 64.77)
		(diameter 0)
		(color 0 0 0 0)
	)
	(junction
		(at 245.11 50.8)
		(diameter 0)
		(color 0 0 0 0)
	)
	(junction
		(at 317.5 63.5)
		(diameter 0)
		(color 0 0 0 0)
	)
	(junction
		(at 323.85 49.53)
		(diameter 0)
		(color 0 0 0 0)
	)
	(junction
		(at 128.27 49.53)
		(diameter 0)
		(color 0 0 0 0)
	)
	(junction
		(at 146.05 63.5)
		(diameter 0)
		(color 0 0 0 0)
	)
	(junction
		(at 41.91 50.8)
		(diameter 0)
		(color 0 0 0 0)
	)
	(junction
		(at 341.63 63.5)
		(diameter 0)
		(color 0 0 0 0)
	)
	(junction
		(at 359.41 152.4)
		(diameter 0)
		(color 0 0 0 0)
	)
	(junction
		(at 33.02 50.8)
		(diameter 0)
		(color 0 0 0 0)
	)
	(junction
		(at 50.8 64.77)
		(diameter 0)
		(color 0 0 0 0)
	)
	(junction
		(at 163.83 101.6)
		(diameter 0)
		(color 0 0 0 0)
	)
	(junction
		(at 57.15 64.77)
		(diameter 0)
		(color 0 0 0 0)
	)
	(junction
		(at 132.08 77.47)
		(diameter 0)
		(color 0 0 0 0)
	)
	(junction
		(at 323.85 63.5)
		(diameter 0)
		(color 0 0 0 0)
	)
	(junction
		(at 146.05 49.53)
		(diameter 0)
		(color 0 0 0 0)
	)
	(no_connect
		(at 252.73 142.24)
	)
	(no_connect
		(at 58.42 88.9)
	)
	(no_connect
		(at 316.23 144.78)
	)
	(no_connect
		(at 58.42 91.44)
	)
	(no_connect
		(at 252.73 99.06)
	)
	(no_connect
		(at 58.42 129.54)
	)
	(no_connect
		(at 58.42 147.32)
	)
	(no_connect
		(at 58.42 152.4)
	)
	(no_connect
		(at 58.42 124.46)
	)
	(no_connect
		(at 316.23 193.04)
	)
	(no_connect
		(at 316.23 88.9)
	)
	(no_connect
		(at 58.42 121.92)
	)
	(no_connect
		(at 58.42 167.64)
	)
	(no_connect
		(at 316.23 119.38)
	)
	(no_connect
		(at 252.73 167.64)
	)
	(no_connect
		(at 58.42 96.52)
	)
	(no_connect
		(at 252.73 114.3)
	)
	(no_connect
		(at 252.73 195.58)
	)
	(no_connect
		(at 316.23 142.24)
	)
	(no_connect
		(at 58.42 106.68)
	)
	(no_connect
		(at 58.42 157.48)
	)
	(no_connect
		(at 58.42 139.7)
	)
	(no_connect
		(at 58.42 162.56)
	)
	(no_connect
		(at 252.73 175.26)
	)
	(no_connect
		(at 252.73 180.34)
	)
	(no_connect
		(at 58.42 160.02)
	)
	(no_connect
		(at 58.42 109.22)
	)
	(no_connect
		(at 121.92 88.9)
	)
	(no_connect
		(at 121.92 193.04)
	)
	(no_connect
		(at 58.42 111.76)
	)
	(no_connect
		(at 316.23 165.1)
	)
	(no_connect
		(at 58.42 127)
	)
	(no_connect
		(at 121.92 185.42)
	)
	(no_connect
		(at 252.73 157.48)
	)
	(no_connect
		(at 58.42 175.26)
	)
	(no_connect
		(at 58.42 142.24)
	)
	(no_connect
		(at 58.42 144.78)
	)
	(no_connect
		(at 58.42 137.16)
	)
	(no_connect
		(at 316.23 96.52)
	)
	(no_connect
		(at 58.42 101.6)
	)
	(no_connect
		(at 121.92 182.88)
	)
	(no_connect
		(at 316.23 149.86)
	)
	(no_connect
		(at 58.42 165.1)
	)
	(no_connect
		(at 316.23 208.28)
	)
	(no_connect
		(at 252.73 104.14)
	)
	(no_connect
		(at 58.42 172.72)
	)
	(no_connect
		(at 121.92 200.66)
	)
	(no_connect
		(at 58.42 149.86)
	)
	(no_connect
		(at 58.42 134.62)
	)
	(no_connect
		(at 58.42 99.06)
	)
	(no_connect
		(at 316.23 157.48)
	)
	(no_connect
		(at 316.23 205.74)
	)
	(no_connect
		(at 58.42 132.08)
	)
	(no_connect
		(at 252.73 116.84)
	)
	(no_connect
		(at 58.42 93.98)
	)
	(no_connect
		(at 58.42 114.3)
	)
	(no_connect
		(at 58.42 104.14)
	)
	(no_connect
		(at 316.23 93.98)
	)
	(no_connect
		(at 58.42 154.94)
	)
	(no_connect
		(at 121.92 198.12)
	)
	(no_connect
		(at 58.42 116.84)
	)
	(no_connect
		(at 58.42 119.38)
	)
	(no_connect
		(at 121.92 213.36)
	)
	(no_connect
		(at 58.42 170.18)
	)
	(wire
		(pts
			(xy 137.16 49.53) (xy 137.16 50.8)
		)
		(stroke
			(width 0)
			(type default)
		)
	)
	(wire
		(pts
			(xy 33.02 50.8) (xy 33.02 52.07)
		)
		(stroke
			(width 0)
			(type default)
		)
	)
	(wire
		(pts
			(xy 121.92 111.76) (xy 139.7 111.76)
		)
		(stroke
			(width 0)
			(type default)
		)
	)
	(wire
		(pts
			(xy 359.41 49.53) (xy 361.95 49.53)
		)
		(stroke
			(width 0)
			(type default)
		)
	)
	(wire
		(pts
			(xy 139.7 132.08) (xy 121.92 132.08)
		)
		(stroke
			(width 0)
			(type default)
		)
	)
	(wire
		(pts
			(xy 341.63 49.53) (xy 341.63 50.8)
		)
		(stroke
			(width 0)
			(type default)
		)
	)
	(wire
		(pts
			(xy 316.23 104.14) (xy 318.77 104.14)
		)
		(stroke
			(width 0)
			(type default)
		)
	)
	(wire
		(pts
			(xy 317.5 63.5) (xy 317.5 85.09)
		)
		(stroke
			(width 0)
			(type default)
		)
	)
	(wire
		(pts
			(xy 137.16 49.53) (xy 128.27 49.53)
		)
		(stroke
			(width 0)
			(type default)
		)
	)
	(wire
		(pts
			(xy 250.19 165.1) (xy 252.73 165.1)
		)
		(stroke
			(width 0)
			(type default)
		)
	)
	(wire
		(pts
			(xy 318.77 190.5) (xy 316.23 190.5)
		)
		(stroke
			(width 0)
			(type default)
		)
	)
	(wire
		(pts
			(xy 139.7 91.44) (xy 121.92 91.44)
		)
		(stroke
			(width 0)
			(type default)
		)
	)
	(wire
		(pts
			(xy 250.19 127) (xy 252.73 127)
		)
		(stroke
			(width 0)
			(type default)
		)
	)
	(wire
		(pts
			(xy 251.46 50.8) (xy 251.46 64.77)
		)
		(stroke
			(width 0)
			(type default)
		)
	)
	(wire
		(pts
			(xy 359.41 49.53) (xy 350.52 49.53)
		)
		(stroke
			(width 0)
			(type default)
		)
	)
	(wire
		(pts
			(xy 146.05 63.5) (xy 137.16 63.5)
		)
		(stroke
			(width 0)
			(type default)
		)
	)
	(wire
		(pts
			(xy 121.92 177.8) (xy 139.7 177.8)
		)
		(stroke
			(width 0)
			(type default)
		)
	)
	(wire
		(pts
			(xy 121.92 203.2) (xy 139.7 203.2)
		)
		(stroke
			(width 0)
			(type default)
		)
	)
	(wire
		(pts
			(xy 252.73 93.98) (xy 250.19 93.98)
		)
		(stroke
			(width 0)
			(type default)
		)
	)
	(wire
		(pts
			(xy 146.05 63.5) (xy 146.05 64.77)
		)
		(stroke
			(width 0)
			(type default)
		)
	)
	(wire
		(pts
			(xy 316.23 139.7) (xy 318.77 139.7)
		)
		(stroke
			(width 0)
			(type default)
		)
	)
	(wire
		(pts
			(xy 323.85 63.5) (xy 323.85 64.77)
		)
		(stroke
			(width 0)
			(type default)
		)
	)
	(wire
		(pts
			(xy 339.09 152.4) (xy 316.23 152.4)
		)
		(stroke
			(width 0)
			(type default)
		)
	)
	(wire
		(pts
			(xy 236.22 64.77) (xy 236.22 66.04)
		)
		(stroke
			(width 0)
			(type default)
		)
	)
	(wire
		(pts
			(xy 124.46 77.47) (xy 124.46 78.74)
		)
		(stroke
			(width 0)
			(type default)
		)
	)
	(wire
		(pts
			(xy 57.15 64.77) (xy 57.15 85.09)
		)
		(stroke
			(width 0)
			(type default)
		)
	)
	(wire
		(pts
			(xy 57.15 50.8) (xy 57.15 64.77)
		)
		(stroke
			(width 0)
			(type default)
		)
	)
	(wire
		(pts
			(xy 137.16 63.5) (xy 128.27 63.5)
		)
		(stroke
			(width 0)
			(type default)
		)
	)
	(wire
		(pts
			(xy 316.23 109.22) (xy 318.77 109.22)
		)
		(stroke
			(width 0)
			(type default)
		)
	)
	(wire
		(pts
			(xy 139.7 93.98) (xy 121.92 93.98)
		)
		(stroke
			(width 0)
			(type default)
		)
	)
	(wire
		(pts
			(xy 316.23 127) (xy 318.77 127)
		)
		(stroke
			(width 0)
			(type default)
		)
	)
	(wire
		(pts
			(xy 121.92 210.82) (xy 139.7 210.82)
		)
		(stroke
			(width 0)
			(type default)
		)
	)
	(wire
		(pts
			(xy 250.19 203.2) (xy 252.73 203.2)
		)
		(stroke
			(width 0)
			(type default)
		)
	)
	(wire
		(pts
			(xy 227.33 50.8) (xy 236.22 50.8)
		)
		(stroke
			(width 0)
			(type default)
		)
	)
	(wire
		(pts
			(xy 250.19 210.82) (xy 252.73 210.82)
		)
		(stroke
			(width 0)
			(type default)
		)
	)
	(wire
		(pts
			(xy 250.19 109.22) (xy 252.73 109.22)
		)
		(stroke
			(width 0)
			(type default)
		)
	)
	(wire
		(pts
			(xy 250.19 149.86) (xy 252.73 149.86)
		)
		(stroke
			(width 0)
			(type default)
		)
	)
	(wire
		(pts
			(xy 350.52 49.53) (xy 341.63 49.53)
		)
		(stroke
			(width 0)
			(type default)
		)
	)
	(wire
		(pts
			(xy 50.8 50.8) (xy 50.8 52.07)
		)
		(stroke
			(width 0)
			(type default)
		)
	)
	(wire
		(pts
			(xy 121.92 190.5) (xy 139.7 190.5)
		)
		(stroke
			(width 0)
			(type default)
		)
	)
	(wire
		(pts
			(xy 368.3 152.4) (xy 365.76 152.4)
		)
		(stroke
			(width 0)
			(type default)
		)
	)
	(wire
		(pts
			(xy 121.92 165.1) (xy 139.7 165.1)
		)
		(stroke
			(width 0)
			(type default)
		)
	)
	(wire
		(pts
			(xy 236.22 64.77) (xy 245.11 64.77)
		)
		(stroke
			(width 0)
			(type default)
		)
	)
	(wire
		(pts
			(xy 121.92 49.53) (xy 121.92 63.5)
		)
		(stroke
			(width 0)
			(type default)
		)
	)
	(wire
		(pts
			(xy 316.23 124.46) (xy 318.77 124.46)
		)
		(stroke
			(width 0)
			(type default)
		)
	)
	(wire
		(pts
			(xy 121.92 104.14) (xy 139.7 104.14)
		)
		(stroke
			(width 0)
			(type default)
		)
	)
	(wire
		(pts
			(xy 359.41 157.48) (xy 359.41 158.75)
		)
		(stroke
			(width 0)
			(type default)
		)
	)
	(wire
		(pts
			(xy 250.19 101.6) (xy 252.73 101.6)
		)
		(stroke
			(width 0)
			(type default)
		)
	)
	(wire
		(pts
			(xy 250.19 193.04) (xy 252.73 193.04)
		)
		(stroke
			(width 0)
			(type default)
		)
	)
	(wire
		(pts
			(xy 318.77 172.72) (xy 316.23 172.72)
		)
		(stroke
			(width 0)
			(type default)
		)
	)
	(wire
		(pts
			(xy 227.33 50.8) (xy 227.33 52.07)
		)
		(stroke
			(width 0)
			(type default)
		)
	)
	(wire
		(pts
			(xy 132.08 77.47) (xy 132.08 85.09)
		)
		(stroke
			(width 0)
			(type default)
		)
	)
	(wire
		(pts
			(xy 316.23 91.44) (xy 318.77 91.44)
		)
		(stroke
			(width 0)
			(type default)
		)
	)
	(wire
		(pts
			(xy 250.19 124.46) (xy 252.73 124.46)
		)
		(stroke
			(width 0)
			(type default)
		)
	)
	(wire
		(pts
			(xy 165.1 93.98) (xy 163.83 93.98)
		)
		(stroke
			(width 0)
			(type default)
		)
	)
	(wire
		(pts
			(xy 154.94 49.53) (xy 154.94 50.8)
		)
		(stroke
			(width 0)
			(type default)
		)
	)
	(wire
		(pts
			(xy 318.77 114.3) (xy 316.23 114.3)
		)
		(stroke
			(width 0)
			(type default)
		)
	)
	(wire
		(pts
			(xy 341.63 49.53) (xy 332.74 49.53)
		)
		(stroke
			(width 0)
			(type default)
		)
	)
	(wire
		(pts
			(xy 163.83 101.6) (xy 163.83 102.87)
		)
		(stroke
			(width 0)
			(type default)
		)
	)
	(wire
		(pts
			(xy 323.85 63.5) (xy 317.5 63.5)
		)
		(stroke
			(width 0)
			(type default)
		)
	)
	(wire
		(pts
			(xy 252.73 132.08) (xy 250.19 132.08)
		)
		(stroke
			(width 0)
			(type default)
		)
	)
	(wire
		(pts
			(xy 250.19 106.68) (xy 252.73 106.68)
		)
		(stroke
			(width 0)
			(type default)
		)
	)
	(polyline
		(pts
			(xy 53.34 86.36) (xy 90.17 86.36)
		)
		(stroke
			(width 0)
			(type dash)
		)
	)
	(wire
		(pts
			(xy 250.19 187.96) (xy 252.73 187.96)
		)
		(stroke
			(width 0)
			(type default)
		)
	)
	(wire
		(pts
			(xy 218.44 50.8) (xy 218.44 52.07)
		)
		(stroke
			(width 0)
			(type default)
		)
	)
	(wire
		(pts
			(xy 139.7 205.74) (xy 121.92 205.74)
		)
		(stroke
			(width 0)
			(type default)
		)
	)
	(wire
		(pts
			(xy 316.23 132.08) (xy 318.77 132.08)
		)
		(stroke
			(width 0)
			(type default)
		)
	)
	(wire
		(pts
			(xy 359.41 49.53) (xy 359.41 50.8)
		)
		(stroke
			(width 0)
			(type default)
		)
	)
	(wire
		(pts
			(xy 250.19 91.44) (xy 252.73 91.44)
		)
		(stroke
			(width 0)
			(type default)
		)
	)
	(wire
		(pts
			(xy 139.7 106.68) (xy 121.92 106.68)
		)
		(stroke
			(width 0)
			(type default)
		)
	)
	(wire
		(pts
			(xy 350.52 63.5) (xy 341.63 63.5)
		)
		(stroke
			(width 0)
			(type default)
		)
	)
	(wire
		(pts
			(xy 132.08 90.17) (xy 132.08 96.52)
		)
		(stroke
			(width 0)
			(type default)
		)
	)
	(wire
		(pts
			(xy 318.77 213.36) (xy 316.23 213.36)
		)
		(stroke
			(width 0)
			(type default)
		)
	)
	(wire
		(pts
			(xy 139.7 149.86) (xy 121.92 149.86)
		)
		(stroke
			(width 0)
			(type default)
		)
	)
	(wire
		(pts
			(xy 41.91 64.77) (xy 41.91 66.04)
		)
		(stroke
			(width 0)
			(type default)
		)
	)
	(wire
		(pts
			(xy 163.83 100.33) (xy 163.83 101.6)
		)
		(stroke
			(width 0)
			(type default)
		)
	)
	(wire
		(pts
			(xy 318.77 154.94) (xy 316.23 154.94)
		)
		(stroke
			(width 0)
			(type default)
		)
	)
	(wire
		(pts
			(xy 252.73 134.62) (xy 250.19 134.62)
		)
		(stroke
			(width 0)
			(type default)
		)
	)
	(wire
		(pts
			(xy 318.77 121.92) (xy 316.23 121.92)
		)
		(stroke
			(width 0)
			(type default)
		)
	)
	(wire
		(pts
			(xy 250.19 205.74) (xy 252.73 205.74)
		)
		(stroke
			(width 0)
			(type default)
		)
	)
	(wire
		(pts
			(xy 250.19 213.36) (xy 252.73 213.36)
		)
		(stroke
			(width 0)
			(type default)
		)
	)
	(wire
		(pts
			(xy 250.19 172.72) (xy 252.73 172.72)
		)
		(stroke
			(width 0)
			(type default)
		)
	)
	(wire
		(pts
			(xy 245.11 64.77) (xy 251.46 64.77)
		)
		(stroke
			(width 0)
			(type default)
		)
	)
	(wire
		(pts
			(xy 250.19 121.92) (xy 252.73 121.92)
		)
		(stroke
			(width 0)
			(type default)
		)
	)
	(wire
		(pts
			(xy 139.7 96.52) (xy 132.08 96.52)
		)
		(stroke
			(width 0)
			(type default)
		)
	)
	(wire
		(pts
			(xy 250.19 111.76) (xy 252.73 111.76)
		)
		(stroke
			(width 0)
			(type default)
		)
	)
	(wire
		(pts
			(xy 139.7 170.18) (xy 121.92 170.18)
		)
		(stroke
			(width 0)
			(type default)
		)
	)
	(wire
		(pts
			(xy 316.23 177.8) (xy 318.77 177.8)
		)
		(stroke
			(width 0)
			(type default)
		)
	)
	(wire
		(pts
			(xy 121.92 187.96) (xy 139.7 187.96)
		)
		(stroke
			(width 0)
			(type default)
		)
	)
	(wire
		(pts
			(xy 316.23 99.06) (xy 318.77 99.06)
		)
		(stroke
			(width 0)
			(type default)
		)
	)
	(wire
		(pts
			(xy 121.92 160.02) (xy 139.7 160.02)
		)
		(stroke
			(width 0)
			(type default)
		)
	)
	(wire
		(pts
			(xy 121.92 208.28) (xy 139.7 208.28)
		)
		(stroke
			(width 0)
			(type default)
		)
	)
	(wire
		(pts
			(xy 316.23 134.62) (xy 318.77 134.62)
		)
		(stroke
			(width 0)
			(type default)
		)
	)
	(wire
		(pts
			(xy 317.5 49.53) (xy 317.5 63.5)
		)
		(stroke
			(width 0)
			(type default)
		)
	)
	(wire
		(pts
			(xy 121.92 63.5) (xy 121.92 77.47)
		)
		(stroke
			(width 0)
			(type default)
		)
	)
	(wire
		(pts
			(xy 30.48 50.8) (xy 33.02 50.8)
		)
		(stroke
			(width 0)
			(type default)
		)
	)
	(wire
		(pts
			(xy 323.85 49.53) (xy 317.5 49.53)
		)
		(stroke
			(width 0)
			(type default)
		)
	)
	(wire
		(pts
			(xy 139.7 129.54) (xy 121.92 129.54)
		)
		(stroke
			(width 0)
			(type default)
		)
	)
	(wire
		(pts
			(xy 250.19 190.5) (xy 252.73 190.5)
		)
		(stroke
			(width 0)
			(type default)
		)
	)
	(wire
		(pts
			(xy 318.77 160.02) (xy 316.23 160.02)
		)
		(stroke
			(width 0)
			(type default)
		)
	)
	(wire
		(pts
			(xy 317.5 85.09) (xy 316.23 85.09)
		)
		(stroke
			(width 0)
			(type default)
		)
	)
	(wire
		(pts
			(xy 121.92 172.72) (xy 139.7 172.72)
		)
		(stroke
			(width 0)
			(type default)
		)
	)
	(wire
		(pts
			(xy 251.46 64.77) (xy 251.46 85.09)
		)
		(stroke
			(width 0)
			(type default)
		)
	)
	(wire
		(pts
			(xy 236.22 50.8) (xy 236.22 52.07)
		)
		(stroke
			(width 0)
			(type default)
		)
	)
	(wire
		(pts
			(xy 139.7 147.32) (xy 121.92 147.32)
		)
		(stroke
			(width 0)
			(type default)
		)
	)
	(wire
		(pts
			(xy 245.11 64.77) (xy 245.11 66.04)
		)
		(stroke
			(width 0)
			(type default)
		)
	)
	(wire
		(pts
			(xy 163.83 107.95) (xy 163.83 109.22)
		)
		(stroke
			(width 0)
			(type default)
		)
	)
	(wire
		(pts
			(xy 316.23 101.6) (xy 318.77 101.6)
		)
		(stroke
			(width 0)
			(type default)
		)
	)
	(wire
		(pts
			(xy 50.8 64.77) (xy 57.15 64.77)
		)
		(stroke
			(width 0)
			(type default)
		)
	)
	(wire
		(pts
			(xy 124.46 83.82) (xy 124.46 116.84)
		)
		(stroke
			(width 0)
			(type default)
		)
	)
	(wire
		(pts
			(xy 139.7 116.84) (xy 134.62 116.84)
		)
		(stroke
			(width 0)
			(type default)
		)
	)
	(wire
		(pts
			(xy 250.19 154.94) (xy 252.73 154.94)
		)
		(stroke
			(width 0)
			(type default)
		)
	)
	(wire
		(pts
			(xy 138.43 99.06) (xy 121.92 99.06)
		)
		(stroke
			(width 0)
			(type default)
		)
	)
	(wire
		(pts
			(xy 250.19 152.4) (xy 252.73 152.4)
		)
		(stroke
			(width 0)
			(type default)
		)
	)
	(wire
		(pts
			(xy 318.77 203.2) (xy 316.23 203.2)
		)
		(stroke
			(width 0)
			(type default)
		)
	)
	(wire
		(pts
			(xy 154.94 49.53) (xy 146.05 49.53)
		)
		(stroke
			(width 0)
			(type default)
		)
	)
	(wire
		(pts
			(xy 251.46 85.09) (xy 252.73 85.09)
		)
		(stroke
			(width 0)
			(type default)
		)
	)
	(wire
		(pts
			(xy 218.44 64.77) (xy 227.33 64.77)
		)
		(stroke
			(width 0)
			(type default)
		)
	)
	(wire
		(pts
			(xy 332.74 63.5) (xy 332.74 64.77)
		)
		(stroke
			(width 0)
			(type default)
		)
	)
	(wire
		(pts
			(xy 137.16 63.5) (xy 137.16 64.77)
		)
		(stroke
			(width 0)
			(type default)
		)
	)
	(wire
		(pts
			(xy 318.77 185.42) (xy 316.23 185.42)
		)
		(stroke
			(width 0)
			(type default)
		)
	)
	(wire
		(pts
			(xy 318.77 198.12) (xy 316.23 198.12)
		)
		(stroke
			(width 0)
			(type default)
		)
	)
	(wire
		(pts
			(xy 250.19 147.32) (xy 252.73 147.32)
		)
		(stroke
			(width 0)
			(type default)
		)
	)
	(wire
		(pts
			(xy 245.11 50.8) (xy 245.11 52.07)
		)
		(stroke
			(width 0)
			(type default)
		)
	)
	(wire
		(pts
			(xy 236.22 50.8) (xy 245.11 50.8)
		)
		(stroke
			(width 0)
			(type default)
		)
	)
	(wire
		(pts
			(xy 250.19 182.88) (xy 252.73 182.88)
		)
		(stroke
			(width 0)
			(type default)
		)
	)
	(wire
		(pts
			(xy 154.94 49.53) (xy 157.48 49.53)
		)
		(stroke
			(width 0)
			(type default)
		)
	)
	(wire
		(pts
			(xy 250.19 119.38) (xy 252.73 119.38)
		)
		(stroke
			(width 0)
			(type default)
		)
	)
	(wire
		(pts
			(xy 121.92 77.47) (xy 121.92 85.09)
		)
		(stroke
			(width 0)
			(type default)
		)
	)
	(wire
		(pts
			(xy 163.83 101.6) (xy 121.92 101.6)
		)
		(stroke
			(width 0)
			(type default)
		)
	)
	(wire
		(pts
			(xy 316.23 116.84) (xy 318.77 116.84)
		)
		(stroke
			(width 0)
			(type default)
		)
	)
	(wire
		(pts
			(xy 146.05 49.53) (xy 146.05 50.8)
		)
		(stroke
			(width 0)
			(type default)
		)
	)
	(wire
		(pts
			(xy 318.77 175.26) (xy 316.23 175.26)
		)
		(stroke
			(width 0)
			(type default)
		)
	)
	(wire
		(pts
			(xy 139.7 99.06) (xy 138.43 99.06)
		)
		(stroke
			(width 0)
			(type default)
		)
	)
	(wire
		(pts
			(xy 218.44 64.77) (xy 218.44 66.04)
		)
		(stroke
			(width 0)
			(type default)
		)
	)
	(wire
		(pts
			(xy 121.92 119.38) (xy 139.7 119.38)
		)
		(stroke
			(width 0)
			(type default)
		)
	)
	(wire
		(pts
			(xy 250.19 200.66) (xy 252.73 200.66)
		)
		(stroke
			(width 0)
			(type default)
		)
	)
	(polyline
		(pts
			(xy 90.17 87.63) (xy 90.17 181.61)
		)
		(stroke
			(width 0)
			(type dash)
		)
	)
	(wire
		(pts
			(xy 359.41 63.5) (xy 350.52 63.5)
		)
		(stroke
			(width 0)
			(type default)
		)
	)
	(wire
		(pts
			(xy 350.52 63.5) (xy 350.52 64.77)
		)
		(stroke
			(width 0)
			(type default)
		)
	)
	(wire
		(pts
			(xy 316.23 106.68) (xy 318.77 106.68)
		)
		(stroke
			(width 0)
			(type default)
		)
	)
	(wire
		(pts
			(xy 250.19 198.12) (xy 252.73 198.12)
		)
		(stroke
			(width 0)
			(type default)
		)
	)
	(wire
		(pts
			(xy 121.92 114.3) (xy 139.7 114.3)
		)
		(stroke
			(width 0)
			(type default)
		)
	)
	(wire
		(pts
			(xy 132.08 77.47) (xy 124.46 77.47)
		)
		(stroke
			(width 0)
			(type default)
		)
	)
	(wire
		(pts
			(xy 350.52 49.53) (xy 350.52 50.8)
		)
		(stroke
			(width 0)
			(type default)
		)
	)
	(wire
		(pts
			(xy 318.77 187.96) (xy 316.23 187.96)
		)
		(stroke
			(width 0)
			(type default)
		)
	)
	(wire
		(pts
			(xy 146.05 49.53) (xy 137.16 49.53)
		)
		(stroke
			(width 0)
			(type default)
		)
	)
	(polyline
		(pts
			(xy 53.34 180.34) (xy 53.34 86.36)
		)
		(stroke
			(width 0)
			(type dash)
		)
	)
	(wire
		(pts
			(xy 250.19 185.42) (xy 252.73 185.42)
		)
		(stroke
			(width 0)
			(type default)
		)
	)
	(wire
		(pts
			(xy 128.27 63.5) (xy 121.92 63.5)
		)
		(stroke
			(width 0)
			(type default)
		)
	)
	(wire
		(pts
			(xy 318.77 180.34) (xy 316.23 180.34)
		)
		(stroke
			(width 0)
			(type default)
		)
	)
	(wire
		(pts
			(xy 139.7 162.56) (xy 121.92 162.56)
		)
		(stroke
			(width 0)
			(type default)
		)
	)
	(wire
		(pts
			(xy 227.33 64.77) (xy 236.22 64.77)
		)
		(stroke
			(width 0)
			(type default)
		)
	)
	(wire
		(pts
			(xy 316.23 129.54) (xy 318.77 129.54)
		)
		(stroke
			(width 0)
			(type default)
		)
	)
	(wire
		(pts
			(xy 121.92 180.34) (xy 139.7 180.34)
		)
		(stroke
			(width 0)
			(type default)
		)
	)
	(wire
		(pts
			(xy 227.33 64.77) (xy 227.33 66.04)
		)
		(stroke
			(width 0)
			(type default)
		)
	)
	(wire
		(pts
			(xy 358.14 154.94) (xy 359.41 154.94)
		)
		(stroke
			(width 0)
			(type default)
		)
	)
	(wire
		(pts
			(xy 41.91 64.77) (xy 50.8 64.77)
		)
		(stroke
			(width 0)
			(type default)
		)
	)
	(wire
		(pts
			(xy 341.63 63.5) (xy 332.74 63.5)
		)
		(stroke
			(width 0)
			(type default)
		)
	)
	(wire
		(pts
			(xy 139.7 142.24) (xy 121.92 142.24)
		)
		(stroke
			(width 0)
			(type default)
		)
	)
	(wire
		(pts
			(xy 316.23 137.16) (xy 318.77 137.16)
		)
		(stroke
			(width 0)
			(type default)
		)
	)
	(wire
		(pts
			(xy 139.7 109.22) (xy 121.92 109.22)
		)
		(stroke
			(width 0)
			(type default)
		)
	)
	(wire
		(pts
			(xy 359.41 152.4) (xy 358.14 152.4)
		)
		(stroke
			(width 0)
			(type default)
		)
	)
	(wire
		(pts
			(xy 318.77 195.58) (xy 316.23 195.58)
		)
		(stroke
			(width 0)
			(type default)
		)
	)
	(wire
		(pts
			(xy 250.19 96.52) (xy 252.73 96.52)
		)
		(stroke
			(width 0)
			(type default)
		)
	)
	(wire
		(pts
			(xy 252.73 144.78) (xy 250.19 144.78)
		)
		(stroke
			(width 0)
			(type default)
		)
	)
	(wire
		(pts
			(xy 316.23 147.32) (xy 318.77 147.32)
		)
		(stroke
			(width 0)
			(type default)
		)
	)
	(wire
		(pts
			(xy 245.11 50.8) (xy 251.46 50.8)
		)
		(stroke
			(width 0)
			(type default)
		)
	)
	(wire
		(pts
			(xy 57.15 85.09) (xy 58.42 85.09)
		)
		(stroke
			(width 0)
			(type default)
		)
	)
	(wire
		(pts
			(xy 139.7 137.16) (xy 121.92 137.16)
		)
		(stroke
			(width 0)
			(type default)
		)
	)
	(wire
		(pts
			(xy 50.8 50.8) (xy 57.15 50.8)
		)
		(stroke
			(width 0)
			(type default)
		)
	)
	(wire
		(pts
			(xy 332.74 49.53) (xy 332.74 50.8)
		)
		(stroke
			(width 0)
			(type default)
		)
	)
	(wire
		(pts
			(xy 252.73 162.56) (xy 250.19 162.56)
		)
		(stroke
			(width 0)
			(type default)
		)
	)
	(wire
		(pts
			(xy 129.54 116.84) (xy 124.46 116.84)
		)
		(stroke
			(width 0)
			(type default)
		)
	)
	(wire
		(pts
			(xy 318.77 170.18) (xy 316.23 170.18)
		)
		(stroke
			(width 0)
			(type default)
		)
	)
	(wire
		(pts
			(xy 250.19 129.54) (xy 252.73 129.54)
		)
		(stroke
			(width 0)
			(type default)
		)
	)
	(wire
		(pts
			(xy 154.94 63.5) (xy 154.94 64.77)
		)
		(stroke
			(width 0)
			(type default)
		)
	)
	(wire
		(pts
			(xy 128.27 49.53) (xy 128.27 50.8)
		)
		(stroke
			(width 0)
			(type default)
		)
	)
	(wire
		(pts
			(xy 365.76 152.4) (xy 365.76 153.67)
		)
		(stroke
			(width 0)
			(type default)
		)
	)
	(wire
		(pts
			(xy 139.7 144.78) (xy 121.92 144.78)
		)
		(stroke
			(width 0)
			(type default)
		)
	)
	(wire
		(pts
			(xy 358.14 157.48) (xy 359.41 157.48)
		)
		(stroke
			(width 0)
			(type default)
		)
	)
	(wire
		(pts
			(xy 138.43 77.47) (xy 132.08 77.47)
		)
		(stroke
			(width 0)
			(type default)
		)
	)
	(wire
		(pts
			(xy 50.8 64.77) (xy 50.8 66.04)
		)
		(stroke
			(width 0)
			(type default)
		)
	)
	(wire
		(pts
			(xy 250.19 170.18) (xy 252.73 170.18)
		)
		(stroke
			(width 0)
			(type default)
		)
	)
	(wire
		(pts
			(xy 318.77 167.64) (xy 316.23 167.64)
		)
		(stroke
			(width 0)
			(type default)
		)
	)
	(polyline
		(pts
			(xy 90.17 180.34) (xy 53.34 180.34)
		)
		(stroke
			(width 0)
			(type dash)
		)
	)
	(wire
		(pts
			(xy 132.08 96.52) (xy 121.92 96.52)
		)
		(stroke
			(width 0)
			(type default)
		)
	)
	(wire
		(pts
			(xy 341.63 63.5) (xy 341.63 64.77)
		)
		(stroke
			(width 0)
			(type default)
		)
	)
	(wire
		(pts
			(xy 359.41 63.5) (xy 359.41 64.77)
		)
		(stroke
			(width 0)
			(type default)
		)
	)
	(wire
		(pts
			(xy 218.44 50.8) (xy 227.33 50.8)
		)
		(stroke
			(width 0)
			(type default)
		)
	)
	(wire
		(pts
			(xy 139.7 139.7) (xy 121.92 139.7)
		)
		(stroke
			(width 0)
			(type default)
		)
	)
	(wire
		(pts
			(xy 250.19 160.02) (xy 252.73 160.02)
		)
		(stroke
			(width 0)
			(type default)
		)
	)
	(wire
		(pts
			(xy 316.23 111.76) (xy 318.77 111.76)
		)
		(stroke
			(width 0)
			(type default)
		)
	)
	(wire
		(pts
			(xy 124.46 116.84) (xy 121.92 116.84)
		)
		(stroke
			(width 0)
			(type default)
		)
	)
	(wire
		(pts
			(xy 139.7 124.46) (xy 121.92 124.46)
		)
		(stroke
			(width 0)
			(type default)
		)
	)
	(wire
		(pts
			(xy 318.77 182.88) (xy 316.23 182.88)
		)
		(stroke
			(width 0)
			(type default)
		)
	)
	(wire
		(pts
			(xy 121.92 157.48) (xy 139.7 157.48)
		)
		(stroke
			(width 0)
			(type default)
		)
	)
	(wire
		(pts
			(xy 250.19 137.16) (xy 252.73 137.16)
		)
		(stroke
			(width 0)
			(type default)
		)
	)
	(wire
		(pts
			(xy 121.92 167.64) (xy 139.7 167.64)
		)
		(stroke
			(width 0)
			(type default)
		)
	)
	(wire
		(pts
			(xy 139.7 121.92) (xy 121.92 121.92)
		)
		(stroke
			(width 0)
			(type default)
		)
	)
	(wire
		(pts
			(xy 138.43 83.82) (xy 138.43 99.06)
		)
		(stroke
			(width 0)
			(type default)
		)
	)
	(wire
		(pts
			(xy 252.73 88.9) (xy 250.19 88.9)
		)
		(stroke
			(width 0)
			(type default)
		)
	)
	(wire
		(pts
			(xy 33.02 50.8) (xy 41.91 50.8)
		)
		(stroke
			(width 0)
			(type default)
		)
	)
	(wire
		(pts
			(xy 250.19 177.8) (xy 252.73 177.8)
		)
		(stroke
			(width 0)
			(type default)
		)
	)
	(wire
		(pts
			(xy 154.94 63.5) (xy 146.05 63.5)
		)
		(stroke
			(width 0)
			(type default)
		)
	)
	(wire
		(pts
			(xy 121.92 154.94) (xy 139.7 154.94)
		)
		(stroke
			(width 0)
			(type default)
		)
	)
	(wire
		(pts
			(xy 128.27 63.5) (xy 128.27 64.77)
		)
		(stroke
			(width 0)
			(type default)
		)
	)
	(wire
		(pts
			(xy 359.41 152.4) (xy 359.41 154.94)
		)
		(stroke
			(width 0)
			(type default)
		)
	)
	(wire
		(pts
			(xy 121.92 152.4) (xy 139.7 152.4)
		)
		(stroke
			(width 0)
			(type default)
		)
	)
	(wire
		(pts
			(xy 128.27 49.53) (xy 121.92 49.53)
		)
		(stroke
			(width 0)
			(type default)
		)
	)
	(wire
		(pts
			(xy 41.91 50.8) (xy 41.91 52.07)
		)
		(stroke
			(width 0)
			(type default)
		)
	)
	(wire
		(pts
			(xy 139.7 175.26) (xy 121.92 175.26)
		)
		(stroke
			(width 0)
			(type default)
		)
	)
	(wire
		(pts
			(xy 250.19 139.7) (xy 252.73 139.7)
		)
		(stroke
			(width 0)
			(type default)
		)
	)
	(wire
		(pts
			(xy 318.77 200.66) (xy 316.23 200.66)
		)
		(stroke
			(width 0)
			(type default)
		)
	)
	(wire
		(pts
			(xy 318.77 162.56) (xy 316.23 162.56)
		)
		(stroke
			(width 0)
			(type default)
		)
	)
	(wire
		(pts
			(xy 121.92 195.58) (xy 139.7 195.58)
		)
		(stroke
			(width 0)
			(type default)
		)
	)
	(wire
		(pts
			(xy 163.83 93.98) (xy 163.83 95.25)
		)
		(stroke
			(width 0)
			(type default)
		)
	)
	(wire
		(pts
			(xy 365.76 152.4) (xy 359.41 152.4)
		)
		(stroke
			(width 0)
			(type default)
		)
	)
	(wire
		(pts
			(xy 138.43 77.47) (xy 138.43 78.74)
		)
		(stroke
			(width 0)
			(type default)
		)
	)
	(wire
		(pts
			(xy 332.74 49.53) (xy 323.85 49.53)
		)
		(stroke
			(width 0)
			(type default)
		)
	)
	(wire
		(pts
			(xy 323.85 49.53) (xy 323.85 50.8)
		)
		(stroke
			(width 0)
			(type default)
		)
	)
	(wire
		(pts
			(xy 218.44 50.8) (xy 215.9 50.8)
		)
		(stroke
			(width 0)
			(type default)
		)
	)
	(wire
		(pts
			(xy 139.7 127) (xy 121.92 127)
		)
		(stroke
			(width 0)
			(type default)
		)
	)
	(wire
		(pts
			(xy 139.7 134.62) (xy 121.92 134.62)
		)
		(stroke
			(width 0)
			(type default)
		)
	)
	(wire
		(pts
			(xy 124.46 77.47) (xy 121.92 77.47)
		)
		(stroke
			(width 0)
			(type default)
		)
	)
	(wire
		(pts
			(xy 250.19 208.28) (xy 252.73 208.28)
		)
		(stroke
			(width 0)
			(type default)
		)
	)
	(wire
		(pts
			(xy 41.91 50.8) (xy 50.8 50.8)
		)
		(stroke
			(width 0)
			(type default)
		)
	)
	(wire
		(pts
			(xy 318.77 210.82) (xy 316.23 210.82)
		)
		(stroke
			(width 0)
			(type default)
		)
	)
	(wire
		(pts
			(xy 332.74 63.5) (xy 323.85 63.5)
		)
		(stroke
			(width 0)
			(type default)
		)
	)
	(label "GCLK100"
		(at 318.77 152.4 0)
		(effects
			(font
				(size 1.27 1.27)
			)
			(justify left bottom)
		)
	)
	(label "PUDC_B"
		(at 135.89 101.6 180)
		(effects
			(font
				(size 1.27 1.27)
			)
			(justify right bottom)
		)
	)
	(global_label "I2C[0]_SDA"
		(shape input)
		(at 250.19 111.76 180)
		(fields_autoplaced yes)
		(effects
			(font
				(size 1.27 1.27)
			)
			(justify right)
		)
		(property "Intersheetrefs" "${INTERSHEET_REFS}"
			(at 84.455 36.83 0)
			(effects
				(font
					(size 1.27 1.27)
				)
				(hide yes)
			)
		)
	)
	(global_label "MMC_CMD"
		(shape input)
		(at 139.7 154.94 0)
		(fields_autoplaced yes)
		(effects
			(font
				(size 1.27 1.27)
			)
			(justify left)
		)
		(property "Intersheetrefs" "${INTERSHEET_REFS}"
			(at 15.875 36.83 0)
			(effects
				(font
					(size 1.27 1.27)
				)
				(justify right)
				(hide yes)
			)
		)
	)
	(global_label "I2C[7]_SDA"
		(shape input)
		(at 318.77 106.68 0)
		(fields_autoplaced yes)
		(effects
			(font
				(size 1.27 1.27)
			)
			(justify left)
		)
		(property "Intersheetrefs" "${INTERSHEET_REFS}"
			(at 331.6171 106.6006 0)
			(effects
				(font
					(size 1.27 1.27)
				)
				(justify left)
				(hide yes)
			)
		)
	)
	(global_label "HPM_STBY_EN_R"
		(shape input)
		(at 139.7 167.64 0)
		(fields_autoplaced yes)
		(effects
			(font
				(size 1.27 1.27)
			)
			(justify left)
		)
		(property "Intersheetrefs" "${INTERSHEET_REFS}"
			(at 15.875 36.83 0)
			(effects
				(font
					(size 1.27 1.27)
				)
				(justify right)
				(hide yes)
			)
		)
	)
	(global_label "RGMII_RXD3"
		(shape output)
		(at 250.19 134.62 180)
		(fields_autoplaced yes)
		(effects
			(font
				(size 1.27 1.27)
			)
			(justify right)
		)
		(property "Intersheetrefs" "${INTERSHEET_REFS}"
			(at 88.265 36.83 0)
			(effects
				(font
					(size 1.27 1.27)
				)
				(hide yes)
			)
		)
	)
	(global_label "ETH_INT_N"
		(shape output)
		(at 250.19 177.8 180)
		(fields_autoplaced yes)
		(effects
			(font
				(size 1.27 1.27)
			)
			(justify right)
		)
		(property "Intersheetrefs" "${INTERSHEET_REFS}"
			(at 88.265 36.83 0)
			(effects
				(font
					(size 1.27 1.27)
				)
				(hide yes)
			)
		)
	)
	(global_label "ESPI_IO2"
		(shape input)
		(at 250.19 205.74 180)
		(fields_autoplaced yes)
		(effects
			(font
				(size 1.27 1.27)
			)
			(justify right)
		)
		(property "Intersheetrefs" "${INTERSHEET_REFS}"
			(at 89.535 36.83 0)
			(effects
				(font
					(size 1.27 1.27)
				)
				(hide yes)
			)
		)
	)
	(global_label "RGMII_TXD1"
		(shape input)
		(at 250.19 127 180)
		(fields_autoplaced yes)
		(effects
			(font
				(size 1.27 1.27)
			)
			(justify right)
		)
		(property "Intersheetrefs" "${INTERSHEET_REFS}"
			(at 88.265 36.83 0)
			(effects
				(font
					(size 1.27 1.27)
				)
				(hide yes)
			)
		)
	)
	(global_label "ULPI1_DATA3"
		(shape input)
		(at 139.7 165.1 0)
		(fields_autoplaced yes)
		(effects
			(font
				(size 1.27 1.27)
			)
			(justify left)
		)
		(property "Intersheetrefs" "${INTERSHEET_REFS}"
			(at 15.875 36.83 0)
			(effects
				(font
					(size 1.27 1.27)
				)
				(justify right)
				(hide yes)
			)
		)
	)
	(global_label "ROT_MOSI"
		(shape input)
		(at 318.77 185.42 0)
		(fields_autoplaced yes)
		(effects
			(font
				(size 1.27 1.27)
			)
			(justify left)
		)
		(property "Intersheetrefs" "${INTERSHEET_REFS}"
			(at 330.2261 185.3406 0)
			(effects
				(font
					(size 1.27 1.27)
				)
				(justify left)
				(hide yes)
			)
		)
	)
	(global_label "I2C[3]_SCL"
		(shape input)
		(at 250.19 185.42 180)
		(fields_autoplaced yes)
		(effects
			(font
				(size 1.27 1.27)
			)
			(justify right)
		)
		(property "Intersheetrefs" "${INTERSHEET_REFS}"
			(at 88.265 36.83 0)
			(effects
				(font
					(size 1.27 1.27)
				)
				(hide yes)
			)
		)
	)
	(global_label "DBG_UART_TX"
		(shape input)
		(at 139.7 114.3 0)
		(fields_autoplaced yes)
		(effects
			(font
				(size 1.27 1.27)
			)
			(justify left)
		)
		(property "Intersheetrefs" "${INTERSHEET_REFS}"
			(at 20.955 36.83 0)
			(effects
				(font
					(size 1.27 1.27)
				)
				(justify right)
				(hide yes)
			)
		)
	)
	(global_label "SPI0_CS_N_R"
		(shape input)
		(at 318.77 114.3 0)
		(fields_autoplaced yes)
		(effects
			(font
				(size 1.27 1.27)
			)
			(justify left)
		)
		(property "Intersheetrefs" "${INTERSHEET_REFS}"
			(at 333.3709 114.2206 0)
			(effects
				(font
					(size 1.27 1.27)
				)
				(justify left)
				(hide yes)
			)
		)
	)
	(global_label "SPI0_MOSI_R"
		(shape input)
		(at 318.77 134.62 0)
		(fields_autoplaced yes)
		(effects
			(font
				(size 1.27 1.27)
			)
			(justify left)
		)
		(property "Intersheetrefs" "${INTERSHEET_REFS}"
			(at 333.1894 134.5406 0)
			(effects
				(font
					(size 1.27 1.27)
				)
				(justify left)
				(hide yes)
			)
		)
	)
	(global_label "ULPI1_RESET"
		(shape input)
		(at 139.7 144.78 0)
		(fields_autoplaced yes)
		(effects
			(font
				(size 1.27 1.27)
			)
			(justify left)
		)
		(property "Intersheetrefs" "${INTERSHEET_REFS}"
			(at 17.145 36.83 0)
			(effects
				(font
					(size 1.27 1.27)
				)
				(justify right)
				(hide yes)
			)
		)
	)
	(global_label "ULPI1_DATA6"
		(shape input)
		(at 139.7 129.54 0)
		(fields_autoplaced yes)
		(effects
			(font
				(size 1.27 1.27)
			)
			(justify left)
		)
		(property "Intersheetrefs" "${INTERSHEET_REFS}"
			(at 15.875 36.83 0)
			(effects
				(font
					(size 1.27 1.27)
				)
				(justify right)
				(hide yes)
			)
		)
	)
	(global_label "ULPI1_STP"
		(shape input)
		(at 139.7 134.62 0)
		(fields_autoplaced yes)
		(effects
			(font
				(size 1.27 1.27)
			)
			(justify left)
		)
		(property "Intersheetrefs" "${INTERSHEET_REFS}"
			(at 15.875 36.83 0)
			(effects
				(font
					(size 1.27 1.27)
				)
				(justify right)
				(hide yes)
			)
		)
	)
	(global_label "RGMII_TXD2"
		(shape input)
		(at 250.19 124.46 180)
		(fields_autoplaced yes)
		(effects
			(font
				(size 1.27 1.27)
			)
			(justify right)
		)
		(property "Intersheetrefs" "${INTERSHEET_REFS}"
			(at 88.265 36.83 0)
			(effects
				(font
					(size 1.27 1.27)
				)
				(hide yes)
			)
		)
	)
	(global_label "ESPI_CS1_N"
		(shape input)
		(at 250.19 96.52 180)
		(fields_autoplaced yes)
		(effects
			(font
				(size 1.27 1.27)
			)
			(justify right)
		)
		(property "Intersheetrefs" "${INTERSHEET_REFS}"
			(at 84.455 36.83 0)
			(effects
				(font
					(size 1.27 1.27)
				)
				(hide yes)
			)
		)
	)
	(global_label "VIRTUAL_RESEAT_R"
		(shape input)
		(at 318.77 198.12 0)
		(fields_autoplaced yes)
		(effects
			(font
				(size 1.27 1.27)
			)
			(justify left)
		)
		(property "Intersheetrefs" "${INTERSHEET_REFS}"
			(at 338.5113 198.0406 0)
			(effects
				(font
					(size 1.27 1.27)
				)
				(justify left)
				(hide yes)
			)
		)
	)
	(global_label "USR_LED2"
		(shape input)
		(at 139.7 149.86 0)
		(fields_autoplaced yes)
		(effects
			(font
				(size 1.27 1.27)
			)
			(justify left)
		)
		(property "Intersheetrefs" "${INTERSHEET_REFS}"
			(at 15.875 36.83 0)
			(effects
				(font
					(size 1.27 1.27)
				)
				(justify right)
				(hide yes)
			)
		)
	)
	(global_label "MMC_RSTN"
		(shape input)
		(at 139.7 160.02 0)
		(fields_autoplaced yes)
		(effects
			(font
				(size 1.27 1.27)
			)
			(justify left)
		)
		(property "Intersheetrefs" "${INTERSHEET_REFS}"
			(at 15.875 36.83 0)
			(effects
				(font
					(size 1.27 1.27)
				)
				(justify right)
				(hide yes)
			)
		)
	)
	(global_label "SPI0_MISO_R"
		(shape input)
		(at 318.77 124.46 0)
		(fields_autoplaced yes)
		(effects
			(font
				(size 1.27 1.27)
			)
			(justify left)
		)
		(property "Intersheetrefs" "${INTERSHEET_REFS}"
			(at 333.1894 124.3806 0)
			(effects
				(font
					(size 1.27 1.27)
				)
				(justify left)
				(hide yes)
			)
		)
	)
	(global_label "ULPI1_DATA2"
		(shape input)
		(at 139.7 162.56 0)
		(fields_autoplaced yes)
		(effects
			(font
				(size 1.27 1.27)
			)
			(justify left)
		)
		(property "Intersheetrefs" "${INTERSHEET_REFS}"
			(at 15.875 36.83 0)
			(effects
				(font
					(size 1.27 1.27)
				)
				(justify right)
				(hide yes)
			)
		)
	)
	(global_label "NCSI_RXER"
		(shape input)
		(at 318.77 104.14 0)
		(fields_autoplaced yes)
		(effects
			(font
				(size 1.27 1.27)
			)
			(justify left)
		)
		(property "Intersheetrefs" "${INTERSHEET_REFS}"
			(at 331.3752 104.0606 0)
			(effects
				(font
					(size 1.27 1.27)
				)
				(justify left)
				(hide yes)
			)
		)
	)
	(global_label "I2C[4]_SCL"
		(shape input)
		(at 250.19 182.88 180)
		(fields_autoplaced yes)
		(effects
			(font
				(size 1.27 1.27)
			)
			(justify right)
		)
		(property "Intersheetrefs" "${INTERSHEET_REFS}"
			(at 88.265 36.83 0)
			(effects
				(font
					(size 1.27 1.27)
				)
				(hide yes)
			)
		)
	)
	(global_label "RGMII_RXD1"
		(shape output)
		(at 250.19 139.7 180)
		(fields_autoplaced yes)
		(effects
			(font
				(size 1.27 1.27)
			)
			(justify right)
		)
		(property "Intersheetrefs" "${INTERSHEET_REFS}"
			(at 88.265 36.83 0)
			(effects
				(font
					(size 1.27 1.27)
				)
				(hide yes)
			)
		)
	)
	(global_label "USR_LED0"
		(shape input)
		(at 139.7 119.38 0)
		(fields_autoplaced yes)
		(effects
			(font
				(size 1.27 1.27)
			)
			(justify left)
		)
		(property "Intersheetrefs" "${INTERSHEET_REFS}"
			(at 15.875 36.83 0)
			(effects
				(font
					(size 1.27 1.27)
				)
				(justify right)
				(hide yes)
			)
		)
	)
	(global_label "TPM_RST"
		(shape input)
		(at 139.7 104.14 0)
		(fields_autoplaced yes)
		(effects
			(font
				(size 1.27 1.27)
			)
			(justify left)
		)
		(property "Intersheetrefs" "${INTERSHEET_REFS}"
			(at 20.955 36.83 0)
			(effects
				(font
					(size 1.27 1.27)
				)
				(justify right)
				(hide yes)
			)
		)
	)
	(global_label "UART1_SCM_TX"
		(shape input)
		(at 139.7 109.22 0)
		(fields_autoplaced yes)
		(effects
			(font
				(size 1.27 1.27)
			)
			(justify left)
		)
		(property "Intersheetrefs" "${INTERSHEET_REFS}"
			(at 20.955 36.83 0)
			(effects
				(font
					(size 1.27 1.27)
				)
				(justify right)
				(hide yes)
			)
		)
	)
	(global_label "HPM_STBY_RDY_R"
		(shape input)
		(at 139.7 208.28 0)
		(fields_autoplaced yes)
		(effects
			(font
				(size 1.27 1.27)
			)
			(justify left)
		)
		(property "Intersheetrefs" "${INTERSHEET_REFS}"
			(at 16.51 36.83 0)
			(effects
				(font
					(size 1.27 1.27)
				)
				(justify right)
				(hide yes)
			)
		)
	)
	(global_label "ROT_GPIO2"
		(shape input)
		(at 318.77 213.36 0)
		(fields_autoplaced yes)
		(effects
			(font
				(size 1.27 1.27)
			)
			(justify left)
		)
		(property "Intersheetrefs" "${INTERSHEET_REFS}"
			(at 331.3147 213.2806 0)
			(effects
				(font
					(size 1.27 1.27)
				)
				(justify left)
				(hide yes)
			)
		)
	)
	(global_label "I3C[1]_SCL_3V3"
		(shape input)
		(at 318.77 182.88 0)
		(fields_autoplaced yes)
		(effects
			(font
				(size 1.27 1.27)
			)
			(justify left)
		)
		(property "Intersheetrefs" "${INTERSHEET_REFS}"
			(at 336.0318 182.8006 0)
			(effects
				(font
					(size 1.27 1.27)
				)
				(justify left)
				(hide yes)
			)
		)
	)
	(global_label "I3C[3]_SCL_3V3"
		(shape input)
		(at 318.77 160.02 0)
		(fields_autoplaced yes)
		(effects
			(font
				(size 1.27 1.27)
			)
			(justify left)
		)
		(property "Intersheetrefs" "${INTERSHEET_REFS}"
			(at 336.0318 159.9406 0)
			(effects
				(font
					(size 1.27 1.27)
				)
				(justify left)
				(hide yes)
			)
		)
	)
	(global_label "RGMII_REF_CLK"
		(shape output)
		(at 250.19 149.86 180)
		(fields_autoplaced yes)
		(effects
			(font
				(size 1.27 1.27)
			)
			(justify right)
		)
		(property "Intersheetrefs" "${INTERSHEET_REFS}"
			(at 88.265 36.83 0)
			(effects
				(font
					(size 1.27 1.27)
				)
				(hide yes)
			)
		)
	)
	(global_label "ROT_RX"
		(shape input)
		(at 318.77 175.26 0)
		(fields_autoplaced yes)
		(effects
			(font
				(size 1.27 1.27)
			)
			(justify left)
		)
		(property "Intersheetrefs" "${INTERSHEET_REFS}"
			(at 328.1094 175.1806 0)
			(effects
				(font
					(size 1.27 1.27)
				)
				(justify left)
				(hide yes)
			)
		)
	)
	(global_label "TPM_PIRQ#"
		(shape input)
		(at 250.19 106.68 180)
		(fields_autoplaced yes)
		(effects
			(font
				(size 1.27 1.27)
			)
			(justify right)
		)
		(property "Intersheetrefs" "${INTERSHEET_REFS}"
			(at 84.455 36.83 0)
			(effects
				(font
					(size 1.27 1.27)
				)
				(hide yes)
			)
		)
	)
	(global_label "NCSI_TXD1"
		(shape input)
		(at 318.77 109.22 0)
		(fields_autoplaced yes)
		(effects
			(font
				(size 1.27 1.27)
			)
			(justify left)
		)
		(property "Intersheetrefs" "${INTERSHEET_REFS}"
			(at 331.1332 109.1406 0)
			(effects
				(font
					(size 1.27 1.27)
				)
				(justify left)
				(hide yes)
			)
		)
	)
	(global_label "RGMII_RXD2"
		(shape output)
		(at 250.19 132.08 180)
		(fields_autoplaced yes)
		(effects
			(font
				(size 1.27 1.27)
			)
			(justify right)
		)
		(property "Intersheetrefs" "${INTERSHEET_REFS}"
			(at 88.265 36.83 0)
			(effects
				(font
					(size 1.27 1.27)
				)
				(hide yes)
			)
		)
	)
	(global_label "I2C[8]_SDA"
		(shape input)
		(at 318.77 101.6 0)
		(fields_autoplaced yes)
		(effects
			(font
				(size 1.27 1.27)
			)
			(justify left)
		)
		(property "Intersheetrefs" "${INTERSHEET_REFS}"
			(at 331.6171 101.5206 0)
			(effects
				(font
					(size 1.27 1.27)
				)
				(justify left)
				(hide yes)
			)
		)
	)
	(global_label "I3C[3]_SDA_3V3"
		(shape input)
		(at 318.77 162.56 0)
		(fields_autoplaced yes)
		(effects
			(font
				(size 1.27 1.27)
			)
			(justify left)
		)
		(property "Intersheetrefs" "${INTERSHEET_REFS}"
			(at 336.0923 162.4806 0)
			(effects
				(font
					(size 1.27 1.27)
				)
				(justify left)
				(hide yes)
			)
		)
	)
	(global_label "I2C[1]_SDA"
		(shape input)
		(at 250.19 208.28 180)
		(fields_autoplaced yes)
		(effects
			(font
				(size 1.27 1.27)
			)
			(justify right)
		)
		(property "Intersheetrefs" "${INTERSHEET_REFS}"
			(at 88.9 36.83 0)
			(effects
				(font
					(size 1.27 1.27)
				)
				(hide yes)
			)
		)
	)
	(global_label "NCSI_CRS_DV"
		(shape input)
		(at 318.77 139.7 0)
		(fields_autoplaced yes)
		(effects
			(font
				(size 1.27 1.27)
			)
			(justify left)
		)
		(property "Intersheetrefs" "${INTERSHEET_REFS}"
			(at 333.5523 139.6206 0)
			(effects
				(font
					(size 1.27 1.27)
				)
				(justify left)
				(hide yes)
			)
		)
	)
	(global_label "ULPI1_DIR"
		(shape input)
		(at 139.7 121.92 0)
		(fields_autoplaced yes)
		(effects
			(font
				(size 1.27 1.27)
			)
			(justify left)
		)
		(property "Intersheetrefs" "${INTERSHEET_REFS}"
			(at 15.875 36.83 0)
			(effects
				(font
					(size 1.27 1.27)
				)
				(justify right)
				(hide yes)
			)
		)
	)
	(global_label "MMC_DAT1"
		(shape input)
		(at 139.7 170.18 0)
		(fields_autoplaced yes)
		(effects
			(font
				(size 1.27 1.27)
			)
			(justify left)
		)
		(property "Intersheetrefs" "${INTERSHEET_REFS}"
			(at 15.875 36.83 0)
			(effects
				(font
					(size 1.27 1.27)
				)
				(justify right)
				(hide yes)
			)
		)
	)
	(global_label "RGMII_TXD3"
		(shape input)
		(at 250.19 144.78 180)
		(fields_autoplaced yes)
		(effects
			(font
				(size 1.27 1.27)
			)
			(justify right)
		)
		(property "Intersheetrefs" "${INTERSHEET_REFS}"
			(at 88.265 36.83 0)
			(effects
				(font
					(size 1.27 1.27)
				)
				(hide yes)
			)
		)
	)
	(global_label "PRSNT0_N_R"
		(shape input)
		(at 318.77 203.2 0)
		(fields_autoplaced yes)
		(effects
			(font
				(size 1.27 1.27)
			)
			(justify left)
		)
		(property "Intersheetrefs" "${INTERSHEET_REFS}"
			(at 332.8871 203.1206 0)
			(effects
				(font
					(size 1.27 1.27)
				)
				(justify left)
				(hide yes)
			)
		)
	)
	(global_label "ESPI_ALERT_N"
		(shape input)
		(at 250.19 119.38 180)
		(fields_autoplaced yes)
		(effects
			(font
				(size 1.27 1.27)
			)
			(justify right)
		)
		(property "Intersheetrefs" "${INTERSHEET_REFS}"
			(at 88.265 36.83 0)
			(effects
				(font
					(size 1.27 1.27)
				)
				(hide yes)
			)
		)
	)
	(global_label "I2C[6]_SDA"
		(shape input)
		(at 250.19 93.98 180)
		(fields_autoplaced yes)
		(effects
			(font
				(size 1.27 1.27)
			)
			(justify right)
		)
		(property "Intersheetrefs" "${INTERSHEET_REFS}"
			(at 84.455 36.83 0)
			(effects
				(font
					(size 1.27 1.27)
				)
				(hide yes)
			)
		)
	)
	(global_label "NCSI_CLK"
		(shape input)
		(at 318.77 129.54 0)
		(fields_autoplaced yes)
		(effects
			(font
				(size 1.27 1.27)
			)
			(justify left)
		)
		(property "Intersheetrefs" "${INTERSHEET_REFS}"
			(at 330.0447 129.4606 0)
			(effects
				(font
					(size 1.27 1.27)
				)
				(justify left)
				(hide yes)
			)
		)
	)
	(global_label "MMC_DAT3"
		(shape input)
		(at 139.7 157.48 0)
		(fields_autoplaced yes)
		(effects
			(font
				(size 1.27 1.27)
			)
			(justify left)
		)
		(property "Intersheetrefs" "${INTERSHEET_REFS}"
			(at 15.875 36.83 0)
			(effects
				(font
					(size 1.27 1.27)
				)
				(justify right)
				(hide yes)
			)
		)
	)
	(global_label "I3C[1]_SDA_3V3"
		(shape input)
		(at 318.77 180.34 0)
		(fields_autoplaced yes)
		(effects
			(font
				(size 1.27 1.27)
			)
			(justify left)
		)
		(property "Intersheetrefs" "${INTERSHEET_REFS}"
			(at 336.0923 180.2606 0)
			(effects
				(font
					(size 1.27 1.27)
				)
				(justify left)
				(hide yes)
			)
		)
	)
	(global_label "MMC_DAT6"
		(shape input)
		(at 139.7 190.5 0)
		(fields_autoplaced yes)
		(effects
			(font
				(size 1.27 1.27)
			)
			(justify left)
		)
		(property "Intersheetrefs" "${INTERSHEET_REFS}"
			(at 16.51 36.83 0)
			(effects
				(font
					(size 1.27 1.27)
				)
				(justify right)
				(hide yes)
			)
		)
	)
	(global_label "ULPI1_DATA1"
		(shape input)
		(at 139.7 172.72 0)
		(fields_autoplaced yes)
		(effects
			(font
				(size 1.27 1.27)
			)
			(justify left)
		)
		(property "Intersheetrefs" "${INTERSHEET_REFS}"
			(at 15.875 36.83 0)
			(effects
				(font
					(size 1.27 1.27)
				)
				(justify right)
				(hide yes)
			)
		)
	)
	(global_label "I3C[0]_SDA_3V3"
		(shape input)
		(at 318.77 167.64 0)
		(fields_autoplaced yes)
		(effects
			(font
				(size 1.27 1.27)
			)
			(justify left)
		)
		(property "Intersheetrefs" "${INTERSHEET_REFS}"
			(at 336.0923 167.5606 0)
			(effects
				(font
					(size 1.27 1.27)
				)
				(justify left)
				(hide yes)
			)
		)
	)
	(global_label "I2C[2]_SDA"
		(shape input)
		(at 250.19 101.6 180)
		(fields_autoplaced yes)
		(effects
			(font
				(size 1.27 1.27)
			)
			(justify right)
		)
		(property "Intersheetrefs" "${INTERSHEET_REFS}"
			(at 84.455 36.83 0)
			(effects
				(font
					(size 1.27 1.27)
				)
				(hide yes)
			)
		)
	)
	(global_label "I3C[2]_SCL_3V3"
		(shape input)
		(at 318.77 154.94 0)
		(fields_autoplaced yes)
		(effects
			(font
				(size 1.27 1.27)
			)
			(justify left)
		)
		(property "Intersheetrefs" "${INTERSHEET_REFS}"
			(at 336.0318 154.8606 0)
			(effects
				(font
					(size 1.27 1.27)
				)
				(justify left)
				(hide yes)
			)
		)
	)
	(global_label "ESPI_CS0_N"
		(shape input)
		(at 250.19 152.4 180)
		(fields_autoplaced yes)
		(effects
			(font
				(size 1.27 1.27)
			)
			(justify right)
		)
		(property "Intersheetrefs" "${INTERSHEET_REFS}"
			(at 88.265 36.83 0)
			(effects
				(font
					(size 1.27 1.27)
				)
				(hide yes)
			)
		)
	)
	(global_label "ROT_SS"
		(shape input)
		(at 318.77 200.66 0)
		(fields_autoplaced yes)
		(effects
			(font
				(size 1.27 1.27)
			)
			(justify left)
		)
		(property "Intersheetrefs" "${INTERSHEET_REFS}"
			(at 328.049 200.5806 0)
			(effects
				(font
					(size 1.27 1.27)
				)
				(justify left)
				(hide yes)
			)
		)
	)
	(global_label "ULPI1_DATA7"
		(shape input)
		(at 139.7 139.7 0)
		(fields_autoplaced yes)
		(effects
			(font
				(size 1.27 1.27)
			)
			(justify left)
		)
		(property "Intersheetrefs" "${INTERSHEET_REFS}"
			(at 15.875 36.83 0)
			(effects
				(font
					(size 1.27 1.27)
				)
				(justify right)
				(hide yes)
			)
		)
	)
	(global_label "RGMII_RX_DV"
		(shape output)
		(at 250.19 165.1 180)
		(fields_autoplaced yes)
		(effects
			(font
				(size 1.27 1.27)
			)
			(justify right)
		)
		(property "Intersheetrefs" "${INTERSHEET_REFS}"
			(at 88.265 36.83 0)
			(effects
				(font
					(size 1.27 1.27)
				)
				(hide yes)
			)
		)
	)
	(global_label "ESPI_RESET_N"
		(shape input)
		(at 250.19 213.36 180)
		(fields_autoplaced yes)
		(effects
			(font
				(size 1.27 1.27)
			)
			(justify right)
		)
		(property "Intersheetrefs" "${INTERSHEET_REFS}"
			(at 89.535 36.83 0)
			(effects
				(font
					(size 1.27 1.27)
				)
				(hide yes)
			)
		)
	)
	(global_label "ESPI_CLK"
		(shape input)
		(at 250.19 170.18 180)
		(fields_autoplaced yes)
		(effects
			(font
				(size 1.27 1.27)
			)
			(justify right)
		)
		(property "Intersheetrefs" "${INTERSHEET_REFS}"
			(at 88.265 36.83 0)
			(effects
				(font
					(size 1.27 1.27)
				)
				(hide yes)
			)
		)
	)
	(global_label "ETH_MDC"
		(shape input)
		(at 250.19 162.56 180)
		(fields_autoplaced yes)
		(effects
			(font
				(size 1.27 1.27)
			)
			(justify right)
		)
		(property "Intersheetrefs" "${INTERSHEET_REFS}"
			(at 88.265 36.83 0)
			(effects
				(font
					(size 1.27 1.27)
				)
				(hide yes)
			)
		)
	)
	(global_label "ESPI_IO0"
		(shape input)
		(at 250.19 193.04 180)
		(fields_autoplaced yes)
		(effects
			(font
				(size 1.27 1.27)
			)
			(justify right)
		)
		(property "Intersheetrefs" "${INTERSHEET_REFS}"
			(at 89.535 36.83 0)
			(effects
				(font
					(size 1.27 1.27)
				)
				(hide yes)
			)
		)
	)
	(global_label "MMC_DAT2"
		(shape input)
		(at 139.7 187.96 0)
		(fields_autoplaced yes)
		(effects
			(font
				(size 1.27 1.27)
			)
			(justify left)
		)
		(property "Intersheetrefs" "${INTERSHEET_REFS}"
			(at 16.51 36.83 0)
			(effects
				(font
					(size 1.27 1.27)
				)
				(justify right)
				(hide yes)
			)
		)
	)
	(global_label "NCSI_TXEN"
		(shape input)
		(at 318.77 137.16 0)
		(fields_autoplaced yes)
		(effects
			(font
				(size 1.27 1.27)
			)
			(justify left)
		)
		(property "Intersheetrefs" "${INTERSHEET_REFS}"
			(at 331.1332 137.0806 0)
			(effects
				(font
					(size 1.27 1.27)
				)
				(justify left)
				(hide yes)
			)
		)
	)
	(global_label "ROT_QSPI_DQ0"
		(shape input)
		(at 139.7 91.44 0)
		(fields_autoplaced yes)
		(effects
			(font
				(size 1.27 1.27)
			)
			(justify left)
		)
		(property "Intersheetrefs" "${INTERSHEET_REFS}"
			(at 12.065 36.83 0)
			(effects
				(font
					(size 1.27 1.27)
				)
				(justify right)
				(hide yes)
			)
		)
	)
	(global_label "ROT_QSPI_DQ2"
		(shape input)
		(at 139.7 96.52 0)
		(fields_autoplaced yes)
		(effects
			(font
				(size 1.27 1.27)
			)
			(justify left)
		)
		(property "Intersheetrefs" "${INTERSHEET_REFS}"
			(at 12.065 36.83 0)
			(effects
				(font
					(size 1.27 1.27)
				)
				(justify right)
				(hide yes)
			)
		)
	)
	(global_label "RGMII_RXD0"
		(shape output)
		(at 250.19 160.02 180)
		(fields_autoplaced yes)
		(effects
			(font
				(size 1.27 1.27)
			)
			(justify right)
		)
		(property "Intersheetrefs" "${INTERSHEET_REFS}"
			(at 88.265 36.83 0)
			(effects
				(font
					(size 1.27 1.27)
				)
				(hide yes)
			)
		)
	)
	(global_label "I2C[5]_SCL"
		(shape input)
		(at 139.7 203.2 0)
		(fields_autoplaced yes)
		(effects
			(font
				(size 1.27 1.27)
			)
			(justify left)
		)
		(property "Intersheetrefs" "${INTERSHEET_REFS}"
			(at 16.51 36.83 0)
			(effects
				(font
					(size 1.27 1.27)
				)
				(justify right)
				(hide yes)
			)
		)
	)
	(global_label "TPM_GPIO"
		(shape input)
		(at 139.7 132.08 0)
		(fields_autoplaced yes)
		(effects
			(font
				(size 1.27 1.27)
			)
			(justify left)
		)
		(property "Intersheetrefs" "${INTERSHEET_REFS}"
			(at 15.875 36.83 0)
			(effects
				(font
					(size 1.27 1.27)
				)
				(justify right)
				(hide yes)
			)
		)
	)
	(global_label "NCSI_RXD0"
		(shape input)
		(at 318.77 132.08 0)
		(fields_autoplaced yes)
		(effects
			(font
				(size 1.27 1.27)
			)
			(justify left)
		)
		(property "Intersheetrefs" "${INTERSHEET_REFS}"
			(at 331.4356 132.0006 0)
			(effects
				(font
					(size 1.27 1.27)
				)
				(justify left)
				(hide yes)
			)
		)
	)
	(global_label "RGMII_TXD0"
		(shape input)
		(at 250.19 129.54 180)
		(fields_autoplaced yes)
		(effects
			(font
				(size 1.27 1.27)
			)
			(justify right)
		)
		(property "Intersheetrefs" "${INTERSHEET_REFS}"
			(at 88.265 36.83 0)
			(effects
				(font
					(size 1.27 1.27)
				)
				(hide yes)
			)
		)
	)
	(global_label "NCSI_TXD0"
		(shape input)
		(at 318.77 116.84 0)
		(fields_autoplaced yes)
		(effects
			(font
				(size 1.27 1.27)
			)
			(justify left)
		)
		(property "Intersheetrefs" "${INTERSHEET_REFS}"
			(at 331.1332 116.7606 0)
			(effects
				(font
					(size 1.27 1.27)
				)
				(justify left)
				(hide yes)
			)
		)
	)
	(global_label "RGMII_RX_CLK"
		(shape output)
		(at 250.19 154.94 180)
		(fields_autoplaced yes)
		(effects
			(font
				(size 1.27 1.27)
			)
			(justify right)
		)
		(property "Intersheetrefs" "${INTERSHEET_REFS}"
			(at 88.265 36.83 0)
			(effects
				(font
					(size 1.27 1.27)
				)
				(hide yes)
			)
		)
	)
	(global_label "I2C[0]_SCL"
		(shape input)
		(at 250.19 88.9 180)
		(fields_autoplaced yes)
		(effects
			(font
				(size 1.27 1.27)
			)
			(justify right)
		)
		(property "Intersheetrefs" "${INTERSHEET_REFS}"
			(at 84.455 36.83 0)
			(effects
				(font
					(size 1.27 1.27)
				)
				(hide yes)
			)
		)
	)
	(global_label "ROT_QSPI_CS_B"
		(shape input)
		(at 139.7 116.84 0)
		(fields_autoplaced yes)
		(effects
			(font
				(size 1.27 1.27)
			)
			(justify left)
		)
		(property "Intersheetrefs" "${INTERSHEET_REFS}"
			(at 10.16 36.83 0)
			(effects
				(font
					(size 1.27 1.27)
				)
				(justify right)
				(hide yes)
			)
		)
	)
	(global_label "DBG_UART_RX"
		(shape input)
		(at 139.7 111.76 0)
		(fields_autoplaced yes)
		(effects
			(font
				(size 1.27 1.27)
			)
			(justify left)
		)
		(property "Intersheetrefs" "${INTERSHEET_REFS}"
			(at 20.955 36.83 0)
			(effects
				(font
					(size 1.27 1.27)
				)
				(justify right)
				(hide yes)
			)
		)
	)
	(global_label "VCC3V3"
		(shape input)
		(at 215.9 50.8 180)
		(fields_autoplaced yes)
		(effects
			(font
				(size 1.27 1.27)
			)
			(justify right)
		)
		(property "Intersheetrefs" "${INTERSHEET_REFS}"
			(at 206.4396 50.8794 0)
			(effects
				(font
					(size 1.27 1.27)
				)
				(justify right)
				(hide yes)
			)
		)
	)
	(global_label "I3C[0]_SCL_3V3"
		(shape input)
		(at 318.77 195.58 0)
		(fields_autoplaced yes)
		(effects
			(font
				(size 1.27 1.27)
			)
			(justify left)
		)
		(property "Intersheetrefs" "${INTERSHEET_REFS}"
			(at 336.0318 195.5006 0)
			(effects
				(font
					(size 1.27 1.27)
				)
				(justify left)
				(hide yes)
			)
		)
	)
	(global_label "USR_LED1"
		(shape input)
		(at 139.7 142.24 0)
		(fields_autoplaced yes)
		(effects
			(font
				(size 1.27 1.27)
			)
			(justify left)
		)
		(property "Intersheetrefs" "${INTERSHEET_REFS}"
			(at 15.875 36.83 0)
			(effects
				(font
					(size 1.27 1.27)
				)
				(justify right)
				(hide yes)
			)
		)
	)
	(global_label "UART0_SCM_RX"
		(shape input)
		(at 318.77 147.32 0)
		(fields_autoplaced yes)
		(effects
			(font
				(size 1.27 1.27)
			)
			(justify left)
		)
		(property "Intersheetrefs" "${INTERSHEET_REFS}"
			(at 335.3061 147.2406 0)
			(effects
				(font
					(size 1.27 1.27)
				)
				(justify left)
				(hide yes)
			)
		)
	)
	(global_label "ESPI_IO1"
		(shape input)
		(at 250.19 210.82 180)
		(fields_autoplaced yes)
		(effects
			(font
				(size 1.27 1.27)
			)
			(justify right)
		)
		(property "Intersheetrefs" "${INTERSHEET_REFS}"
			(at 89.535 36.83 0)
			(effects
				(font
					(size 1.27 1.27)
				)
				(hide yes)
			)
		)
	)
	(global_label "I2C[7]_SCL"
		(shape input)
		(at 318.77 91.44 0)
		(fields_autoplaced yes)
		(effects
			(font
				(size 1.27 1.27)
			)
			(justify left)
		)
		(property "Intersheetrefs" "${INTERSHEET_REFS}"
			(at 331.5566 91.3606 0)
			(effects
				(font
					(size 1.27 1.27)
				)
				(justify left)
				(hide yes)
			)
		)
	)
	(global_label "ROT_MISO"
		(shape input)
		(at 318.77 187.96 0)
		(fields_autoplaced yes)
		(effects
			(font
				(size 1.27 1.27)
			)
			(justify left)
		)
		(property "Intersheetrefs" "${INTERSHEET_REFS}"
			(at 330.2261 187.8806 0)
			(effects
				(font
					(size 1.27 1.27)
				)
				(justify left)
				(hide yes)
			)
		)
	)
	(global_label "ULPI1_DATA5"
		(shape input)
		(at 139.7 137.16 0)
		(fields_autoplaced yes)
		(effects
			(font
				(size 1.27 1.27)
			)
			(justify left)
		)
		(property "Intersheetrefs" "${INTERSHEET_REFS}"
			(at 15.875 36.83 0)
			(effects
				(font
					(size 1.27 1.27)
				)
				(justify right)
				(hide yes)
			)
		)
	)
	(global_label "MMC_DAT7"
		(shape input)
		(at 139.7 210.82 0)
		(fields_autoplaced yes)
		(effects
			(font
				(size 1.27 1.27)
			)
			(justify left)
		)
		(property "Intersheetrefs" "${INTERSHEET_REFS}"
			(at 16.51 36.83 0)
			(effects
				(font
					(size 1.27 1.27)
				)
				(justify right)
				(hide yes)
			)
		)
	)
	(global_label "ESPI_IO3"
		(shape input)
		(at 250.19 203.2 180)
		(fields_autoplaced yes)
		(effects
			(font
				(size 1.27 1.27)
			)
			(justify right)
		)
		(property "Intersheetrefs" "${INTERSHEET_REFS}"
			(at 89.535 36.83 0)
			(effects
				(font
					(size 1.27 1.27)
				)
				(hide yes)
			)
		)
	)
	(global_label "MMC_DAT4"
		(shape input)
		(at 139.7 180.34 0)
		(fields_autoplaced yes)
		(effects
			(font
				(size 1.27 1.27)
			)
			(justify left)
		)
		(property "Intersheetrefs" "${INTERSHEET_REFS}"
			(at 16.51 36.83 0)
			(effects
				(font
					(size 1.27 1.27)
				)
				(justify right)
				(hide yes)
			)
		)
	)
	(global_label "I3C[2]_SDA_3V3"
		(shape input)
		(at 318.77 177.8 0)
		(fields_autoplaced yes)
		(effects
			(font
				(size 1.27 1.27)
			)
			(justify left)
		)
		(property "Intersheetrefs" "${INTERSHEET_REFS}"
			(at 336.0923 177.7206 0)
			(effects
				(font
					(size 1.27 1.27)
				)
				(justify left)
				(hide yes)
			)
		)
	)
	(global_label "RGMII_TX_CLK"
		(shape input)
		(at 250.19 147.32 180)
		(fields_autoplaced yes)
		(effects
			(font
				(size 1.27 1.27)
			)
			(justify right)
		)
		(property "Intersheetrefs" "${INTERSHEET_REFS}"
			(at 88.265 36.83 0)
			(effects
				(font
					(size 1.27 1.27)
				)
				(hide yes)
			)
		)
	)
	(global_label "ROT_QSPI_DQ3"
		(shape input)
		(at 139.7 99.06 0)
		(fields_autoplaced yes)
		(effects
			(font
				(size 1.27 1.27)
			)
			(justify left)
		)
		(property "Intersheetrefs" "${INTERSHEET_REFS}"
			(at 12.065 36.83 0)
			(effects
				(font
					(size 1.27 1.27)
				)
				(justify right)
				(hide yes)
			)
		)
	)
	(global_label "I2C[4]_SDA"
		(shape input)
		(at 250.19 190.5 180)
		(fields_autoplaced yes)
		(effects
			(font
				(size 1.27 1.27)
			)
			(justify right)
		)
		(property "Intersheetrefs" "${INTERSHEET_REFS}"
			(at 89.535 36.83 0)
			(effects
				(font
					(size 1.27 1.27)
				)
				(hide yes)
			)
		)
	)
	(global_label "I2C[8]_SCL"
		(shape input)
		(at 318.77 127 0)
		(fields_autoplaced yes)
		(effects
			(font
				(size 1.27 1.27)
			)
			(justify left)
		)
		(property "Intersheetrefs" "${INTERSHEET_REFS}"
			(at 331.5566 126.9206 0)
			(effects
				(font
					(size 1.27 1.27)
				)
				(justify left)
				(hide yes)
			)
		)
	)
	(global_label "ROT_RDY\\ROT_GPIO0"
		(shape input)
		(at 318.77 190.5 0)
		(fields_autoplaced yes)
		(effects
			(font
				(size 1.27 1.27)
			)
			(justify left)
		)
		(property "Intersheetrefs" "${INTERSHEET_REFS}"
			(at 340.3256 190.4206 0)
			(effects
				(font
					(size 1.27 1.27)
				)
				(justify left)
				(hide yes)
			)
		)
	)
	(global_label "ROT_GPIO1"
		(shape input)
		(at 318.77 210.82 0)
		(fields_autoplaced yes)
		(effects
			(font
				(size 1.27 1.27)
			)
			(justify left)
		)
		(property "Intersheetrefs" "${INTERSHEET_REFS}"
			(at 331.3147 210.7406 0)
			(effects
				(font
					(size 1.27 1.27)
				)
				(justify left)
				(hide yes)
			)
		)
	)
	(global_label "ETH_MDIO"
		(shape bidirectional)
		(at 250.19 137.16 180)
		(fields_autoplaced yes)
		(effects
			(font
				(size 1.27 1.27)
			)
			(justify right)
		)
		(property "Intersheetrefs" "${INTERSHEET_REFS}"
			(at 88.265 36.83 0)
			(effects
				(font
					(size 1.27 1.27)
				)
				(hide yes)
			)
		)
	)
	(global_label "SPI0_CLK_R"
		(shape input)
		(at 318.77 111.76 0)
		(fields_autoplaced yes)
		(effects
			(font
				(size 1.27 1.27)
			)
			(justify left)
		)
		(property "Intersheetrefs" "${INTERSHEET_REFS}"
			(at 332.1613 111.6806 0)
			(effects
				(font
					(size 1.27 1.27)
				)
				(justify left)
				(hide yes)
			)
		)
	)
	(global_label "ROT_QSPI_DQ1"
		(shape input)
		(at 139.7 93.98 0)
		(fields_autoplaced yes)
		(effects
			(font
				(size 1.27 1.27)
			)
			(justify left)
		)
		(property "Intersheetrefs" "${INTERSHEET_REFS}"
			(at 12.065 36.83 0)
			(effects
				(font
					(size 1.27 1.27)
				)
				(justify right)
				(hide yes)
			)
		)
	)
	(global_label "ETH_~{RESET}"
		(shape passive)
		(at 250.19 172.72 180)
		(fields_autoplaced yes)
		(effects
			(font
				(size 1.27 1.27)
			)
			(justify right)
		)
		(property "Intersheetrefs" "${INTERSHEET_REFS}"
			(at 88.265 36.83 0)
			(effects
				(font
					(size 1.27 1.27)
				)
				(hide yes)
			)
		)
	)
	(global_label "MMC_DAT0"
		(shape input)
		(at 139.7 195.58 0)
		(fields_autoplaced yes)
		(effects
			(font
				(size 1.27 1.27)
			)
			(justify left)
		)
		(property "Intersheetrefs" "${INTERSHEET_REFS}"
			(at 16.51 36.83 0)
			(effects
				(font
					(size 1.27 1.27)
				)
				(justify right)
				(hide yes)
			)
		)
	)
	(global_label "VCC3V3"
		(shape input)
		(at 361.95 49.53 0)
		(fields_autoplaced yes)
		(effects
			(font
				(size 1.27 1.27)
			)
			(justify left)
		)
		(property "Intersheetrefs" "${INTERSHEET_REFS}"
			(at 371.4104 49.6094 0)
			(effects
				(font
					(size 1.27 1.27)
				)
				(justify left)
				(hide yes)
			)
		)
	)
	(global_label "ROT_TX"
		(shape input)
		(at 318.77 170.18 0)
		(fields_autoplaced yes)
		(effects
			(font
				(size 1.27 1.27)
			)
			(justify left)
		)
		(property "Intersheetrefs" "${INTERSHEET_REFS}"
			(at 327.8071 170.1006 0)
			(effects
				(font
					(size 1.27 1.27)
				)
				(justify left)
				(hide yes)
			)
		)
	)
	(global_label "UART0_SCM_TX"
		(shape input)
		(at 318.77 99.06 0)
		(fields_autoplaced yes)
		(effects
			(font
				(size 1.27 1.27)
			)
			(justify left)
		)
		(property "Intersheetrefs" "${INTERSHEET_REFS}"
			(at 335.0037 98.9806 0)
			(effects
				(font
					(size 1.27 1.27)
				)
				(justify left)
				(hide yes)
			)
		)
	)
	(global_label "MMC_DAT5"
		(shape input)
		(at 139.7 177.8 0)
		(fields_autoplaced yes)
		(effects
			(font
				(size 1.27 1.27)
			)
			(justify left)
		)
		(property "Intersheetrefs" "${INTERSHEET_REFS}"
			(at 16.51 36.83 0)
			(effects
				(font
					(size 1.27 1.27)
				)
				(justify right)
				(hide yes)
			)
		)
	)
	(global_label "ULPI1_CLKOUT"
		(shape input)
		(at 139.7 147.32 0)
		(fields_autoplaced yes)
		(effects
			(font
				(size 1.27 1.27)
			)
			(justify left)
		)
		(property "Intersheetrefs" "${INTERSHEET_REFS}"
			(at 17.145 36.83 0)
			(effects
				(font
					(size 1.27 1.27)
				)
				(justify right)
				(hide yes)
			)
		)
	)
	(global_label "UART1_SCM_RX"
		(shape input)
		(at 139.7 106.68 0)
		(fields_autoplaced yes)
		(effects
			(font
				(size 1.27 1.27)
			)
			(justify left)
		)
		(property "Intersheetrefs" "${INTERSHEET_REFS}"
			(at 20.955 36.83 0)
			(effects
				(font
					(size 1.27 1.27)
				)
				(justify right)
				(hide yes)
			)
		)
	)
	(global_label "I2C[1]_SCL"
		(shape input)
		(at 250.19 200.66 180)
		(fields_autoplaced yes)
		(effects
			(font
				(size 1.27 1.27)
			)
			(justify right)
		)
		(property "Intersheetrefs" "${INTERSHEET_REFS}"
			(at 88.9 36.83 0)
			(effects
				(font
					(size 1.27 1.27)
				)
				(hide yes)
			)
		)
	)
	(global_label "MMC_CLK"
		(shape input)
		(at 139.7 152.4 0)
		(fields_autoplaced yes)
		(effects
			(font
				(size 1.27 1.27)
			)
			(justify left)
		)
		(property "Intersheetrefs" "${INTERSHEET_REFS}"
			(at 15.875 36.83 0)
			(effects
				(font
					(size 1.27 1.27)
				)
				(justify right)
				(hide yes)
			)
		)
	)
	(global_label "I2C[3]_SDA"
		(shape input)
		(at 250.19 187.96 180)
		(fields_autoplaced yes)
		(effects
			(font
				(size 1.27 1.27)
			)
			(justify right)
		)
		(property "Intersheetrefs" "${INTERSHEET_REFS}"
			(at 89.535 36.83 0)
			(effects
				(font
					(size 1.27 1.27)
				)
				(hide yes)
			)
		)
	)
	(global_label "I2C[5]_SDA"
		(shape input)
		(at 139.7 205.74 0)
		(fields_autoplaced yes)
		(effects
			(font
				(size 1.27 1.27)
			)
			(justify left)
		)
		(property "Intersheetrefs" "${INTERSHEET_REFS}"
			(at 16.51 36.83 0)
			(effects
				(font
					(size 1.27 1.27)
				)
				(justify right)
				(hide yes)
			)
		)
	)
	(global_label "ULPI1_NXT"
		(shape input)
		(at 139.7 124.46 0)
		(fields_autoplaced yes)
		(effects
			(font
				(size 1.27 1.27)
			)
			(justify left)
		)
		(property "Intersheetrefs" "${INTERSHEET_REFS}"
			(at 15.875 36.83 0)
			(effects
				(font
					(size 1.27 1.27)
				)
				(justify right)
				(hide yes)
			)
		)
	)
	(global_label "ROT_SCLK"
		(shape input)
		(at 318.77 172.72 0)
		(fields_autoplaced yes)
		(effects
			(font
				(size 1.27 1.27)
			)
			(justify left)
		)
		(property "Intersheetrefs" "${INTERSHEET_REFS}"
			(at 330.4075 172.6406 0)
			(effects
				(font
					(size 1.27 1.27)
				)
				(justify left)
				(hide yes)
			)
		)
	)
	(global_label "I2C[2]_SCL"
		(shape input)
		(at 250.19 198.12 180)
		(fields_autoplaced yes)
		(effects
			(font
				(size 1.27 1.27)
			)
			(justify right)
		)
		(property "Intersheetrefs" "${INTERSHEET_REFS}"
			(at 88.9 36.83 0)
			(effects
				(font
					(size 1.27 1.27)
				)
				(hide yes)
			)
		)
	)
	(global_label "NCSI_RXD1"
		(shape input)
		(at 318.77 121.92 0)
		(fields_autoplaced yes)
		(effects
			(font
				(size 1.27 1.27)
			)
			(justify left)
		)
		(property "Intersheetrefs" "${INTERSHEET_REFS}"
			(at 331.4356 121.8406 0)
			(effects
				(font
					(size 1.27 1.27)
				)
				(justify left)
				(hide yes)
			)
		)
	)
	(global_label "ULPI1_DATA4"
		(shape input)
		(at 139.7 127 0)
		(fields_autoplaced yes)
		(effects
			(font
				(size 1.27 1.27)
			)
			(justify left)
		)
		(property "Intersheetrefs" "${INTERSHEET_REFS}"
			(at 15.875 36.83 0)
			(effects
				(font
					(size 1.27 1.27)
				)
				(justify right)
				(hide yes)
			)
		)
	)
	(global_label "TPM_PP"
		(shape input)
		(at 250.19 109.22 180)
		(fields_autoplaced yes)
		(effects
			(font
				(size 1.27 1.27)
			)
			(justify right)
		)
		(property "Intersheetrefs" "${INTERSHEET_REFS}"
			(at 84.455 36.83 0)
			(effects
				(font
					(size 1.27 1.27)
				)
				(hide yes)
			)
		)
	)
	(global_label "VCC3V3"
		(shape input)
		(at 368.3 152.4 0)
		(fields_autoplaced yes)
		(effects
			(font
				(size 1.27 1.27)
			)
			(justify left)
		)
		(property "Intersheetrefs" "${INTERSHEET_REFS}"
			(at 694.055 -85.725 0)
			(effects
				(font
					(size 1.27 1.27)
				)
				(hide yes)
			)
		)
	)
	(global_label "VCC3V3"
		(shape input)
		(at 165.1 93.98 0)
		(fields_autoplaced yes)
		(effects
			(font
				(size 1.27 1.27)
			)
			(justify left)
		)
		(property "Intersheetrefs" "${INTERSHEET_REFS}"
			(at 370.84 281.94 0)
			(effects
				(font
					(size 1.27 1.27)
				)
				(hide yes)
			)
		)
	)
	(global_label "VCC3V3"
		(shape input)
		(at 30.48 50.8 180)
		(fields_autoplaced yes)
		(effects
			(font
				(size 1.27 1.27)
			)
			(justify right)
		)
		(property "Intersheetrefs" "${INTERSHEET_REFS}"
			(at 21.0196 50.8794 0)
			(effects
				(font
					(size 1.27 1.27)
				)
				(justify right)
				(hide yes)
			)
		)
	)
	(global_label "RGMII_TX_DV"
		(shape input)
		(at 250.19 121.92 180)
		(fields_autoplaced yes)
		(effects
			(font
				(size 1.27 1.27)
			)
			(justify right)
		)
		(property "Intersheetrefs" "${INTERSHEET_REFS}"
			(at 88.265 36.83 0)
			(effects
				(font
					(size 1.27 1.27)
				)
				(hide yes)
			)
		)
	)
	(global_label "ULPI1_DATA0"
		(shape input)
		(at 139.7 175.26 0)
		(fields_autoplaced yes)
		(effects
			(font
				(size 1.27 1.27)
			)
			(justify left)
		)
		(property "Intersheetrefs" "${INTERSHEET_REFS}"
			(at 15.875 36.83 0)
			(effects
				(font
					(size 1.27 1.27)
				)
				(justify right)
				(hide yes)
			)
		)
	)
	(global_label "I2C[6]_SCL"
		(shape input)
		(at 250.19 91.44 180)
		(fields_autoplaced yes)
		(effects
			(font
				(size 1.27 1.27)
			)
			(justify right)
		)
		(property "Intersheetrefs" "${INTERSHEET_REFS}"
			(at 84.455 36.83 0)
			(effects
				(font
					(size 1.27 1.27)
				)
				(hide yes)
			)
		)
	)
	(global_label "VCC3V3"
		(shape input)
		(at 157.48 49.53 0)
		(fields_autoplaced yes)
		(effects
			(font
				(size 1.27 1.27)
			)
			(justify left)
		)
		(property "Intersheetrefs" "${INTERSHEET_REFS}"
			(at 166.9404 49.6094 0)
			(effects
				(font
					(size 1.27 1.27)
				)
				(justify left)
				(hide yes)
			)
		)
	)
	(symbol
		(lib_id "antmicroCapacitors0402:C_470n_0402")
		(at 41.91 71.12 90)
		(unit 1)
		(exclude_from_sim no)
		(in_bom yes)
		(on_board yes)
		(dnp no)
		(property "Reference" "C125"
			(at 42.545 66.675 90)
			(effects
				(font
					(size 1.27 1.27)
				)
				(justify right)
			)
		)
		(property "Value" "C_470n_0402"
			(at 52.07 50.8 0)
			(effects
				(font
					(size 1.27 1.27)
					(thickness 0.15)
				)
				(justify left bottom)
				(hide yes)
			)
		)
		(property "Footprint" "antmicro-footprints:C_0402_1005Metric"
			(at 54.61 50.8 0)
			(effects
				(font
					(size 1.27 1.27)
					(thickness 0.15)
				)
				(justify left bottom)
				(hide yes)
			)
		)
		(property "Datasheet" "https://product.tdk.com/en/search/capacitor/ceramic/mlcc/info?part_no=C1005X5R1E474M050BB"
			(at 57.15 50.8 0)
			(effects
				(font
					(size 1.27 1.27)
					(thickness 0.15)
				)
				(justify left bottom)
				(hide yes)
			)
		)
		(property "Description" "SMD Multilayer Ceramic Capacitor, 0.47 µF, 25 V, 0402 [1005 Metric], ± 20%, X5R, C"
			(at 41.91 71.12 0)
			(effects
				(font
					(size 1.27 1.27)
				)
				(hide yes)
			)
		)
		(property "Manufacturer" "TDK"
			(at 62.23 50.8 0)
			(effects
				(font
					(size 1.27 1.27)
					(thickness 0.15)
				)
				(justify left bottom)
				(hide yes)
			)
		)
		(property "MPN" "C1005X5R1E474M050BB"
			(at 59.69 50.8 0)
			(effects
				(font
					(size 1.27 1.27)
					(thickness 0.15)
				)
				(justify left bottom)
				(hide yes)
			)
		)
		(property "Val" "470n"
			(at 42.545 70.485 90)
			(effects
				(font
					(size 1.27 1.27)
					(thickness 0.15)
				)
				(justify right)
			)
		)
		(property "License" "Apache-2.0"
			(at 64.77 50.8 0)
			(effects
				(font
					(size 1.27 1.27)
					(thickness 0.15)
				)
				(justify left bottom)
				(hide yes)
			)
		)
		(property "Author" "Antmicro"
			(at 67.31 50.8 0)
			(effects
				(font
					(size 1.27 1.27)
					(thickness 0.15)
				)
				(justify left bottom)
				(hide yes)
			)
		)
		(property "Voltage" ""
			(at 69.85 50.8 0)
			(effects
				(font
					(size 1.27 1.27)
				)
				(justify left bottom)
				(hide yes)
			)
		)
		(property "Dielectric" ""
			(at 72.39 50.8 0)
			(effects
				(font
					(size 1.27 1.27)
				)
				(justify left bottom)
				(hide yes)
			)
		)
		(pin "1"
		)
		(pin "2"
		)
		(instances
			(project "artix-dc-scm"
				(path ""
					(reference "C125")
					(unit 1)
				)
			)
		)
	)
	(symbol
		(lib_id "antmicropower:GND")
		(at 359.41 69.85 0)
		(mirror y)
		(unit 1)
		(exclude_from_sim no)
		(in_bom yes)
		(on_board yes)
		(dnp no)
		(property "Reference" "#PWR016"
			(at 359.41 76.2 0)
			(effects
				(font
					(size 1.27 1.27)
				)
				(hide yes)
			)
		)
		(property "Value" "GND"
			(at 359.41 73.66 0)
			(effects
				(font
					(size 1.27 1.27)
				)
			)
		)
		(property "Footprint" ""
			(at 359.41 69.85 0)
			(effects
				(font
					(size 1.27 1.27)
				)
				(hide yes)
			)
		)
		(property "Datasheet" ""
			(at 359.41 69.85 0)
			(effects
				(font
					(size 1.27 1.27)
				)
				(hide yes)
			)
		)
		(property "Description" ""
			(at 359.41 69.85 0)
			(effects
				(font
					(size 1.27 1.27)
				)
				(hide yes)
			)
		)
		(property "Author" "Antmicro"
			(at 350.52 77.47 0)
			(effects
				(font
					(size 1.27 1.27)
					(thickness 0.15)
				)
				(justify left bottom)
				(hide yes)
			)
		)
		(property "License" "Apache-2.0"
			(at 350.52 80.01 0)
			(effects
				(font
					(size 1.27 1.27)
					(thickness 0.15)
				)
				(justify left bottom)
				(hide yes)
			)
		)
		(pin "1"
		)
		(instances
			(project "artix-dc-scm"
				(path ""
					(reference "#PWR016")
					(unit 1)
				)
			)
		)
	)
	(symbol
		(lib_id "antmicroCapacitors0402:C_470n_0402")
		(at 332.74 69.85 270)
		(mirror x)
		(unit 1)
		(exclude_from_sim no)
		(in_bom yes)
		(on_board yes)
		(dnp no)
		(property "Reference" "C236"
			(at 332.105 65.405 90)
			(effects
				(font
					(size 1.27 1.27)
				)
				(justify right)
			)
		)
		(property "Value" "C_470n_0402"
			(at 322.58 49.53 0)
			(effects
				(font
					(size 1.27 1.27)
					(thickness 0.15)
				)
				(justify left bottom)
				(hide yes)
			)
		)
		(property "Footprint" "antmicro-footprints:C_0402_1005Metric"
			(at 320.04 49.53 0)
			(effects
				(font
					(size 1.27 1.27)
					(thickness 0.15)
				)
				(justify left bottom)
				(hide yes)
			)
		)
		(property "Datasheet" "https://product.tdk.com/en/search/capacitor/ceramic/mlcc/info?part_no=C1005X5R1E474M050BB"
			(at 317.5 49.53 0)
			(effects
				(font
					(size 1.27 1.27)
					(thickness 0.15)
				)
				(justify left bottom)
				(hide yes)
			)
		)
		(property "Description" "SMD Multilayer Ceramic Capacitor, 0.47 µF, 25 V, 0402 [1005 Metric], ± 20%, X5R, C"
			(at 332.74 69.85 0)
			(effects
				(font
					(size 1.27 1.27)
				)
				(hide yes)
			)
		)
		(property "Manufacturer" "TDK"
			(at 312.42 49.53 0)
			(effects
				(font
					(size 1.27 1.27)
					(thickness 0.15)
				)
				(justify left bottom)
				(hide yes)
			)
		)
		(property "MPN" "C1005X5R1E474M050BB"
			(at 314.96 49.53 0)
			(effects
				(font
					(size 1.27 1.27)
					(thickness 0.15)
				)
				(justify left bottom)
				(hide yes)
			)
		)
		(property "Val" "470n"
			(at 332.105 69.215 90)
			(effects
				(font
					(size 1.27 1.27)
					(thickness 0.15)
				)
				(justify right)
			)
		)
		(property "License" "Apache-2.0"
			(at 309.88 49.53 0)
			(effects
				(font
					(size 1.27 1.27)
					(thickness 0.15)
				)
				(justify left bottom)
				(hide yes)
			)
		)
		(property "Author" "Antmicro"
			(at 307.34 49.53 0)
			(effects
				(font
					(size 1.27 1.27)
					(thickness 0.15)
				)
				(justify left bottom)
				(hide yes)
			)
		)
		(property "Voltage" ""
			(at 304.8 49.53 0)
			(effects
				(font
					(size 1.27 1.27)
				)
				(justify left bottom)
				(hide yes)
			)
		)
		(property "Dielectric" ""
			(at 302.26 49.53 0)
			(effects
				(font
					(size 1.27 1.27)
				)
				(justify left bottom)
				(hide yes)
			)
		)
		(property "DNP" ""
			(at 332.74 69.85 0)
			(effects
				(font
					(size 1.27 1.27)
				)
			)
		)
		(pin "1"
		)
		(pin "2"
		)
		(instances
			(project "artix-dc-scm"
				(path ""
					(reference "C236")
					(unit 1)
				)
			)
		)
	)
	(symbol
		(lib_id "antmicroCapacitors0603:C_4u7_0603")
		(at 236.22 57.15 90)
		(unit 1)
		(exclude_from_sim no)
		(in_bom yes)
		(on_board yes)
		(dnp no)
		(property "Reference" "C105"
			(at 236.855 52.705 90)
			(effects
				(font
					(size 1.27 1.27)
				)
				(justify right)
			)
		)
		(property "Value" "C_4u7_0603"
			(at 246.38 36.83 0)
			(effects
				(font
					(size 1.27 1.27)
					(thickness 0.15)
				)
				(justify left bottom)
				(hide yes)
			)
		)
		(property "Footprint" "antmicro-footprints:C_0603_1608Metric"
			(at 248.92 36.83 0)
			(effects
				(font
					(size 1.27 1.27)
					(thickness 0.15)
				)
				(justify left bottom)
				(hide yes)
			)
		)
		(property "Datasheet" "https://product.tdk.com/en/search/capacitor/ceramic/mlcc/info?part_no=C1608X5R1V475M080AC"
			(at 251.46 36.83 0)
			(effects
				(font
					(size 1.27 1.27)
					(thickness 0.15)
				)
				(justify left bottom)
				(hide yes)
			)
		)
		(property "Description" "SMD Multilayer Ceramic Capacitor, 4.7 µF, 35 V, 0603 [1608 Metric], ± 20%, X5R, C"
			(at 236.22 57.15 0)
			(effects
				(font
					(size 1.27 1.27)
				)
				(hide yes)
			)
		)
		(property "Manufacturer" "TDK"
			(at 256.54 36.83 0)
			(effects
				(font
					(size 1.27 1.27)
					(thickness 0.15)
				)
				(justify left bottom)
				(hide yes)
			)
		)
		(property "MPN" "C1608X5R1V475M080AC"
			(at 254 36.83 0)
			(effects
				(font
					(size 1.27 1.27)
					(thickness 0.15)
				)
				(justify left bottom)
				(hide yes)
			)
		)
		(property "Val" "4u7"
			(at 236.855 56.515 90)
			(effects
				(font
					(size 1.27 1.27)
					(thickness 0.15)
				)
				(justify right)
			)
		)
		(property "License" "Apache-2.0"
			(at 259.08 36.83 0)
			(effects
				(font
					(size 1.27 1.27)
					(thickness 0.15)
				)
				(justify left bottom)
				(hide yes)
			)
		)
		(property "Author" "Antmicro"
			(at 261.62 36.83 0)
			(effects
				(font
					(size 1.27 1.27)
					(thickness 0.15)
				)
				(justify left bottom)
				(hide yes)
			)
		)
		(property "Voltage" ""
			(at 264.16 36.83 0)
			(effects
				(font
					(size 1.27 1.27)
				)
				(justify left bottom)
				(hide yes)
			)
		)
		(property "Dielectric" ""
			(at 266.7 36.83 0)
			(effects
				(font
					(size 1.27 1.27)
				)
				(justify left bottom)
				(hide yes)
			)
		)
		(pin "1"
		)
		(pin "2"
		)
		(instances
			(project "artix-dc-scm"
				(path ""
					(reference "C105")
					(unit 1)
				)
			)
		)
	)
	(symbol
		(lib_id "antmicroResistors0402:R_1k_0402")
		(at 163.83 102.87 90)
		(mirror x)
		(unit 1)
		(exclude_from_sim no)
		(in_bom yes)
		(on_board yes)
		(dnp no)
		(property "Reference" "R2"
			(at 162.56 104.14 90)
			(effects
				(font
					(size 1.27 1.27)
				)
				(justify left)
			)
		)
		(property "Value" "R_1k_0402"
			(at 176.53 123.19 0)
			(effects
				(font
					(size 1.27 1.27)
					(thickness 0.15)
				)
				(justify left bottom)
				(hide yes)
			)
		)
		(property "Footprint" "antmicro-footprints:R_0402_1005Metric"
			(at 179.07 123.19 0)
			(effects
				(font
					(size 1.27 1.27)
					(thickness 0.15)
				)
				(justify left bottom)
				(hide yes)
			)
		)
		(property "Datasheet" "https://www.bourns.com/docs/product-datasheets/cr.pdf"
			(at 181.61 123.19 0)
			(effects
				(font
					(size 1.27 1.27)
					(thickness 0.15)
				)
				(justify left bottom)
				(hide yes)
			)
		)
		(property "Description" "SMD Chip Resistor, 1 kohm, ± 1%, 63 mW, 0402 [1005 Metric], Thick Film, General Purpose"
			(at 163.83 102.87 0)
			(effects
				(font
					(size 1.27 1.27)
				)
				(hide yes)
			)
		)
		(property "Manufacturer" "Bourns"
			(at 186.69 123.19 0)
			(effects
				(font
					(size 1.27 1.27)
					(thickness 0.15)
				)
				(justify left bottom)
				(hide yes)
			)
		)
		(property "MPN" "CR0402-FX-1001GLF"
			(at 184.15 123.19 0)
			(effects
				(font
					(size 1.27 1.27)
					(thickness 0.15)
				)
				(justify left bottom)
				(hide yes)
			)
		)
		(property "Val" "1k"
			(at 162.56 106.68 90)
			(effects
				(font
					(size 1.27 1.27)
					(thickness 0.15)
				)
				(justify left)
			)
		)
		(property "License" "Apache-2.0"
			(at 189.23 123.19 0)
			(effects
				(font
					(size 1.27 1.27)
					(thickness 0.15)
				)
				(justify left bottom)
				(hide yes)
			)
		)
		(property "Author" "Antmicro"
			(at 191.77 123.19 0)
			(effects
				(font
					(size 1.27 1.27)
					(thickness 0.15)
				)
				(justify left bottom)
				(hide yes)
			)
		)
		(property "Tolerance" "1%"
			(at 173.99 123.19 0)
			(effects
				(font
					(size 1.27 1.27)
				)
				(justify left bottom)
				(hide yes)
			)
		)
		(property "DNP" ""
			(at 163.83 105.41 0)
			(effects
				(font
					(size 1.27 1.27)
				)
			)
		)
		(pin "1"
		)
		(pin "2"
		)
		(instances
			(project "artix-dc-scm"
				(path ""
					(reference "R2")
					(unit 1)
				)
			)
		)
	)
	(symbol
		(lib_id "antmicroResistors0402:R_2k2_0402")
		(at 124.46 78.74 270)
		(unit 1)
		(exclude_from_sim no)
		(in_bom yes)
		(on_board yes)
		(dnp no)
		(property "Reference" "R133"
			(at 125.73 80.01 90)
			(effects
				(font
					(size 1.27 1.27)
				)
				(justify left)
			)
		)
		(property "Value" "R_2k2_0402"
			(at 111.76 99.06 0)
			(effects
				(font
					(size 1.27 1.27)
					(thickness 0.15)
				)
				(justify left bottom)
				(hide yes)
			)
		)
		(property "Footprint" "antmicro-footprints:R_0402_1005Metric"
			(at 109.22 99.06 0)
			(effects
				(font
					(size 1.27 1.27)
					(thickness 0.15)
				)
				(justify left bottom)
				(hide yes)
			)
		)
		(property "Datasheet" "https://www.bourns.com/docs/product-datasheets/cr.pdf"
			(at 106.68 99.06 0)
			(effects
				(font
					(size 1.27 1.27)
					(thickness 0.15)
				)
				(justify left bottom)
				(hide yes)
			)
		)
		(property "Description" "SMD Chip Resistor, 2.2 kohm, ± 1%, 62.5 mW, 0402 [1005 Metric], Thick Film, General Purpose"
			(at 124.46 78.74 0)
			(effects
				(font
					(size 1.27 1.27)
				)
				(hide yes)
			)
		)
		(property "Manufacturer" "Bourns"
			(at 101.6 99.06 0)
			(effects
				(font
					(size 1.27 1.27)
					(thickness 0.15)
				)
				(justify left bottom)
				(hide yes)
			)
		)
		(property "MPN" "CR0402-FX-2201GLF"
			(at 104.14 99.06 0)
			(effects
				(font
					(size 1.27 1.27)
					(thickness 0.15)
				)
				(justify left bottom)
				(hide yes)
			)
		)
		(property "Val" "2k2"
			(at 125.73 82.55 90)
			(effects
				(font
					(size 1.27 1.27)
					(thickness 0.15)
				)
				(justify left)
			)
		)
		(property "License" "Apache-2.0"
			(at 99.06 99.06 0)
			(effects
				(font
					(size 1.27 1.27)
					(thickness 0.15)
				)
				(justify left bottom)
				(hide yes)
			)
		)
		(property "Author" "Antmicro"
			(at 96.52 99.06 0)
			(effects
				(font
					(size 1.27 1.27)
					(thickness 0.15)
				)
				(justify left bottom)
				(hide yes)
			)
		)
		(property "Tolerance" "1%"
			(at 114.3 99.06 0)
			(effects
				(font
					(size 1.27 1.27)
				)
				(justify left bottom)
				(hide yes)
			)
		)
		(property "DNP" ""
			(at 124.46 78.74 0)
			(effects
				(font
					(size 1.27 1.27)
				)
			)
		)
		(pin "1"
		)
		(pin "2"
		)
		(instances
			(project "artix-dc-scm"
				(path ""
					(reference "R133")
					(unit 1)
				)
			)
		)
	)
	(symbol
		(lib_id "antmicroResistors0402:R_4k7_0402")
		(at 138.43 78.74 270)
		(unit 1)
		(exclude_from_sim no)
		(in_bom yes)
		(on_board yes)
		(dnp no)
		(property "Reference" "R135"
			(at 139.7 80.01 90)
			(effects
				(font
					(size 1.27 1.27)
				)
				(justify left)
			)
		)
		(property "Value" "R_4k7_0402"
			(at 125.73 99.06 0)
			(effects
				(font
					(size 1.27 1.27)
					(thickness 0.15)
				)
				(justify left bottom)
				(hide yes)
			)
		)
		(property "Footprint" "antmicro-footprints:R_0402_1005Metric"
			(at 123.19 99.06 0)
			(effects
				(font
					(size 1.27 1.27)
					(thickness 0.15)
				)
				(justify left bottom)
				(hide yes)
			)
		)
		(property "Datasheet" "https://www.bourns.com/docs/product-datasheets/cr.pdf"
			(at 120.65 99.06 0)
			(effects
				(font
					(size 1.27 1.27)
					(thickness 0.15)
				)
				(justify left bottom)
				(hide yes)
			)
		)
		(property "Description" "SMD Chip Resistor, 4.7 kohm, ± 1%, 62.5 mW, 0402 [1005 Metric], Thick Film, General Purpose"
			(at 138.43 78.74 0)
			(effects
				(font
					(size 1.27 1.27)
				)
				(hide yes)
			)
		)
		(property "Manufacturer" "Bourns"
			(at 115.57 99.06 0)
			(effects
				(font
					(size 1.27 1.27)
					(thickness 0.15)
				)
				(justify left bottom)
				(hide yes)
			)
		)
		(property "MPN" "CR0402-FX-4701GLF"
			(at 118.11 99.06 0)
			(effects
				(font
					(size 1.27 1.27)
					(thickness 0.15)
				)
				(justify left bottom)
				(hide yes)
			)
		)
		(property "Val" "4k7"
			(at 139.7 82.55 90)
			(effects
				(font
					(size 1.27 1.27)
					(thickness 0.15)
				)
				(justify left)
			)
		)
		(property "License" "Apache-2.0"
			(at 113.03 99.06 0)
			(effects
				(font
					(size 1.27 1.27)
					(thickness 0.15)
				)
				(justify left bottom)
				(hide yes)
			)
		)
		(property "Author" "Antmicro"
			(at 110.49 99.06 0)
			(effects
				(font
					(size 1.27 1.27)
					(thickness 0.15)
				)
				(justify left bottom)
				(hide yes)
			)
		)
		(property "Tolerance" "1%"
			(at 128.27 99.06 0)
			(effects
				(font
					(size 1.27 1.27)
				)
				(justify left bottom)
				(hide yes)
			)
		)
		(property "DNP" ""
			(at 138.43 78.74 0)
			(effects
				(font
					(size 1.27 1.27)
				)
			)
		)
		(pin "1"
		)
		(pin "2"
		)
		(instances
			(project "artix-dc-scm"
				(path ""
					(reference "R135")
					(unit 1)
				)
			)
		)
	)
	(symbol
		(lib_id "antmicropower:GND")
		(at 323.85 55.88 0)
		(mirror y)
		(unit 1)
		(exclude_from_sim no)
		(in_bom yes)
		(on_board yes)
		(dnp no)
		(property "Reference" "#PWR027"
			(at 323.85 62.23 0)
			(effects
				(font
					(size 1.27 1.27)
				)
				(hide yes)
			)
		)
		(property "Value" "GND"
			(at 323.85 59.69 0)
			(effects
				(font
					(size 1.27 1.27)
				)
			)
		)
		(property "Footprint" ""
			(at 323.85 55.88 0)
			(effects
				(font
					(size 1.27 1.27)
				)
				(hide yes)
			)
		)
		(property "Datasheet" ""
			(at 323.85 55.88 0)
			(effects
				(font
					(size 1.27 1.27)
				)
				(hide yes)
			)
		)
		(property "Description" ""
			(at 323.85 55.88 0)
			(effects
				(font
					(size 1.27 1.27)
				)
				(hide yes)
			)
		)
		(property "Author" "Antmicro"
			(at 314.96 63.5 0)
			(effects
				(font
					(size 1.27 1.27)
					(thickness 0.15)
				)
				(justify left bottom)
				(hide yes)
			)
		)
		(property "License" "Apache-2.0"
			(at 314.96 66.04 0)
			(effects
				(font
					(size 1.27 1.27)
					(thickness 0.15)
				)
				(justify left bottom)
				(hide yes)
			)
		)
		(pin "1"
		)
		(instances
			(project "artix-dc-scm"
				(path ""
					(reference "#PWR027")
					(unit 1)
				)
			)
		)
	)
	(symbol
		(lib_id "antmicropower:GND")
		(at 41.91 57.15 0)
		(unit 1)
		(exclude_from_sim no)
		(in_bom yes)
		(on_board yes)
		(dnp no)
		(property "Reference" "#PWR0214"
			(at 41.91 63.5 0)
			(effects
				(font
					(size 1.27 1.27)
				)
				(hide yes)
			)
		)
		(property "Value" "GND"
			(at 41.91 60.96 0)
			(effects
				(font
					(size 1.27 1.27)
				)
			)
		)
		(property "Footprint" ""
			(at 41.91 57.15 0)
			(effects
				(font
					(size 1.27 1.27)
				)
				(hide yes)
			)
		)
		(property "Datasheet" ""
			(at 41.91 57.15 0)
			(effects
				(font
					(size 1.27 1.27)
				)
				(hide yes)
			)
		)
		(property "Description" ""
			(at 41.91 57.15 0)
			(effects
				(font
					(size 1.27 1.27)
				)
				(hide yes)
			)
		)
		(property "Author" "Antmicro"
			(at 50.8 64.77 0)
			(effects
				(font
					(size 1.27 1.27)
					(thickness 0.15)
				)
				(justify left bottom)
				(hide yes)
			)
		)
		(property "License" "Apache-2.0"
			(at 50.8 67.31 0)
			(effects
				(font
					(size 1.27 1.27)
					(thickness 0.15)
				)
				(justify left bottom)
				(hide yes)
			)
		)
		(pin "1"
		)
		(instances
			(project "artix-dc-scm"
				(path ""
					(reference "#PWR0214")
					(unit 1)
				)
			)
		)
	)
	(symbol
		(lib_id "antmicroResistors0402:R_4k7_0402")
		(at 132.08 85.09 90)
		(mirror x)
		(unit 1)
		(exclude_from_sim no)
		(in_bom yes)
		(on_board yes)
		(dnp no)
		(property "Reference" "R134"
			(at 133.35 86.36 90)
			(effects
				(font
					(size 1.27 1.27)
				)
				(justify right)
			)
		)
		(property "Value" "R_4k7_0402"
			(at 144.78 105.41 0)
			(effects
				(font
					(size 1.27 1.27)
					(thickness 0.15)
				)
				(justify left bottom)
				(hide yes)
			)
		)
		(property "Footprint" "antmicro-footprints:R_0402_1005Metric"
			(at 147.32 105.41 0)
			(effects
				(font
					(size 1.27 1.27)
					(thickness 0.15)
				)
				(justify left bottom)
				(hide yes)
			)
		)
		(property "Datasheet" "https://www.bourns.com/docs/product-datasheets/cr.pdf"
			(at 149.86 105.41 0)
			(effects
				(font
					(size 1.27 1.27)
					(thickness 0.15)
				)
				(justify left bottom)
				(hide yes)
			)
		)
		(property "Description" "SMD Chip Resistor, 4.7 kohm, ± 1%, 62.5 mW, 0402 [1005 Metric], Thick Film, General Purpose"
			(at 132.08 85.09 0)
			(effects
				(font
					(size 1.27 1.27)
				)
				(hide yes)
			)
		)
		(property "Manufacturer" "Bourns"
			(at 154.94 105.41 0)
			(effects
				(font
					(size 1.27 1.27)
					(thickness 0.15)
				)
				(justify left bottom)
				(hide yes)
			)
		)
		(property "MPN" "CR0402-FX-4701GLF"
			(at 152.4 105.41 0)
			(effects
				(font
					(size 1.27 1.27)
					(thickness 0.15)
				)
				(justify left bottom)
				(hide yes)
			)
		)
		(property "Val" "4k7"
			(at 133.35 88.9 90)
			(effects
				(font
					(size 1.27 1.27)
					(thickness 0.15)
				)
				(justify right)
			)
		)
		(property "License" "Apache-2.0"
			(at 157.48 105.41 0)
			(effects
				(font
					(size 1.27 1.27)
					(thickness 0.15)
				)
				(justify left bottom)
				(hide yes)
			)
		)
		(property "Author" "Antmicro"
			(at 160.02 105.41 0)
			(effects
				(font
					(size 1.27 1.27)
					(thickness 0.15)
				)
				(justify left bottom)
				(hide yes)
			)
		)
		(property "Tolerance" "1%"
			(at 142.24 105.41 0)
			(effects
				(font
					(size 1.27 1.27)
				)
				(justify left bottom)
				(hide yes)
			)
		)
		(pin "1"
		)
		(pin "2"
		)
		(instances
			(project "artix-dc-scm"
				(path ""
					(reference "R134")
					(unit 1)
				)
			)
		)
	)
	(symbol
		(lib_id "antmicropower:GND")
		(at 128.27 69.85 0)
		(mirror y)
		(unit 1)
		(exclude_from_sim no)
		(in_bom yes)
		(on_board yes)
		(dnp no)
		(property "Reference" "#PWR013"
			(at 128.27 76.2 0)
			(effects
				(font
					(size 1.27 1.27)
				)
				(hide yes)
			)
		)
		(property "Value" "GND"
			(at 128.27 73.66 0)
			(effects
				(font
					(size 1.27 1.27)
				)
			)
		)
		(property "Footprint" ""
			(at 128.27 69.85 0)
			(effects
				(font
					(size 1.27 1.27)
				)
				(hide yes)
			)
		)
		(property "Datasheet" ""
			(at 128.27 69.85 0)
			(effects
				(font
					(size 1.27 1.27)
				)
				(hide yes)
			)
		)
		(property "Description" ""
			(at 128.27 69.85 0)
			(effects
				(font
					(size 1.27 1.27)
				)
				(hide yes)
			)
		)
		(property "Author" "Antmicro"
			(at 119.38 77.47 0)
			(effects
				(font
					(size 1.27 1.27)
					(thickness 0.15)
				)
				(justify left bottom)
				(hide yes)
			)
		)
		(property "License" "Apache-2.0"
			(at 119.38 80.01 0)
			(effects
				(font
					(size 1.27 1.27)
					(thickness 0.15)
				)
				(justify left bottom)
				(hide yes)
			)
		)
		(pin "1"
		)
		(instances
			(project "artix-dc-scm"
				(path ""
					(reference "#PWR013")
					(unit 1)
				)
			)
		)
	)
	(symbol
		(lib_id "antmicroCapacitors0603:C_4u7_0603")
		(at 146.05 55.88 270)
		(mirror x)
		(unit 1)
		(exclude_from_sim no)
		(in_bom yes)
		(on_board yes)
		(dnp no)
		(property "Reference" "C100"
			(at 145.415 51.435 90)
			(effects
				(font
					(size 1.27 1.27)
				)
				(justify right)
			)
		)
		(property "Value" "C_4u7_0603"
			(at 135.89 35.56 0)
			(effects
				(font
					(size 1.27 1.27)
					(thickness 0.15)
				)
				(justify left bottom)
				(hide yes)
			)
		)
		(property "Footprint" "antmicro-footprints:C_0603_1608Metric"
			(at 133.35 35.56 0)
			(effects
				(font
					(size 1.27 1.27)
					(thickness 0.15)
				)
				(justify left bottom)
				(hide yes)
			)
		)
		(property "Datasheet" "https://product.tdk.com/en/search/capacitor/ceramic/mlcc/info?part_no=C1608X5R1V475M080AC"
			(at 130.81 35.56 0)
			(effects
				(font
					(size 1.27 1.27)
					(thickness 0.15)
				)
				(justify left bottom)
				(hide yes)
			)
		)
		(property "Description" "SMD Multilayer Ceramic Capacitor, 4.7 µF, 35 V, 0603 [1608 Metric], ± 20%, X5R, C"
			(at 146.05 55.88 0)
			(effects
				(font
					(size 1.27 1.27)
				)
				(hide yes)
			)
		)
		(property "Manufacturer" "TDK"
			(at 125.73 35.56 0)
			(effects
				(font
					(size 1.27 1.27)
					(thickness 0.15)
				)
				(justify left bottom)
				(hide yes)
			)
		)
		(property "MPN" "C1608X5R1V475M080AC"
			(at 128.27 35.56 0)
			(effects
				(font
					(size 1.27 1.27)
					(thickness 0.15)
				)
				(justify left bottom)
				(hide yes)
			)
		)
		(property "Val" "4u7"
			(at 145.415 55.245 90)
			(effects
				(font
					(size 1.27 1.27)
					(thickness 0.15)
				)
				(justify right)
			)
		)
		(property "License" "Apache-2.0"
			(at 123.19 35.56 0)
			(effects
				(font
					(size 1.27 1.27)
					(thickness 0.15)
				)
				(justify left bottom)
				(hide yes)
			)
		)
		(property "Author" "Antmicro"
			(at 120.65 35.56 0)
			(effects
				(font
					(size 1.27 1.27)
					(thickness 0.15)
				)
				(justify left bottom)
				(hide yes)
			)
		)
		(property "Voltage" ""
			(at 118.11 35.56 0)
			(effects
				(font
					(size 1.27 1.27)
				)
				(justify left bottom)
				(hide yes)
			)
		)
		(property "Dielectric" ""
			(at 115.57 35.56 0)
			(effects
				(font
					(size 1.27 1.27)
				)
				(justify left bottom)
				(hide yes)
			)
		)
		(property "DNP" ""
			(at 146.05 55.88 0)
			(effects
				(font
					(size 1.27 1.27)
				)
			)
		)
		(pin "1"
		)
		(pin "2"
		)
		(instances
			(project "artix-dc-scm"
				(path ""
					(reference "C100")
					(unit 1)
				)
			)
		)
	)
	(symbol
		(lib_id "antmicropower:GND")
		(at 332.74 69.85 0)
		(mirror y)
		(unit 1)
		(exclude_from_sim no)
		(in_bom yes)
		(on_board yes)
		(dnp no)
		(property "Reference" "#PWR023"
			(at 332.74 76.2 0)
			(effects
				(font
					(size 1.27 1.27)
				)
				(hide yes)
			)
		)
		(property "Value" "GND"
			(at 332.74 73.66 0)
			(effects
				(font
					(size 1.27 1.27)
				)
			)
		)
		(property "Footprint" ""
			(at 332.74 69.85 0)
			(effects
				(font
					(size 1.27 1.27)
				)
				(hide yes)
			)
		)
		(property "Datasheet" ""
			(at 332.74 69.85 0)
			(effects
				(font
					(size 1.27 1.27)
				)
				(hide yes)
			)
		)
		(property "Description" ""
			(at 332.74 69.85 0)
			(effects
				(font
					(size 1.27 1.27)
				)
				(hide yes)
			)
		)
		(property "Author" "Antmicro"
			(at 323.85 77.47 0)
			(effects
				(font
					(size 1.27 1.27)
					(thickness 0.15)
				)
				(justify left bottom)
				(hide yes)
			)
		)
		(property "License" "Apache-2.0"
			(at 323.85 80.01 0)
			(effects
				(font
					(size 1.27 1.27)
					(thickness 0.15)
				)
				(justify left bottom)
				(hide yes)
			)
		)
		(pin "1"
		)
		(instances
			(project "artix-dc-scm"
				(path ""
					(reference "#PWR023")
					(unit 1)
				)
			)
		)
	)
	(symbol
		(lib_id "antmicroCapacitors0603:C_4u7_0603")
		(at 227.33 57.15 90)
		(unit 1)
		(exclude_from_sim no)
		(in_bom yes)
		(on_board yes)
		(dnp no)
		(property "Reference" "C99"
			(at 227.965 52.705 90)
			(effects
				(font
					(size 1.27 1.27)
				)
				(justify right)
			)
		)
		(property "Value" "C_4u7_0603"
			(at 237.49 36.83 0)
			(effects
				(font
					(size 1.27 1.27)
					(thickness 0.15)
				)
				(justify left bottom)
				(hide yes)
			)
		)
		(property "Footprint" "antmicro-footprints:C_0603_1608Metric"
			(at 240.03 36.83 0)
			(effects
				(font
					(size 1.27 1.27)
					(thickness 0.15)
				)
				(justify left bottom)
				(hide yes)
			)
		)
		(property "Datasheet" "https://product.tdk.com/en/search/capacitor/ceramic/mlcc/info?part_no=C1608X5R1V475M080AC"
			(at 242.57 36.83 0)
			(effects
				(font
					(size 1.27 1.27)
					(thickness 0.15)
				)
				(justify left bottom)
				(hide yes)
			)
		)
		(property "Description" "SMD Multilayer Ceramic Capacitor, 4.7 µF, 35 V, 0603 [1608 Metric], ± 20%, X5R, C"
			(at 227.33 57.15 0)
			(effects
				(font
					(size 1.27 1.27)
				)
				(hide yes)
			)
		)
		(property "Manufacturer" "TDK"
			(at 247.65 36.83 0)
			(effects
				(font
					(size 1.27 1.27)
					(thickness 0.15)
				)
				(justify left bottom)
				(hide yes)
			)
		)
		(property "MPN" "C1608X5R1V475M080AC"
			(at 245.11 36.83 0)
			(effects
				(font
					(size 1.27 1.27)
					(thickness 0.15)
				)
				(justify left bottom)
				(hide yes)
			)
		)
		(property "Val" "4u7"
			(at 227.965 56.515 90)
			(effects
				(font
					(size 1.27 1.27)
					(thickness 0.15)
				)
				(justify right)
			)
		)
		(property "License" "Apache-2.0"
			(at 250.19 36.83 0)
			(effects
				(font
					(size 1.27 1.27)
					(thickness 0.15)
				)
				(justify left bottom)
				(hide yes)
			)
		)
		(property "Author" "Antmicro"
			(at 252.73 36.83 0)
			(effects
				(font
					(size 1.27 1.27)
					(thickness 0.15)
				)
				(justify left bottom)
				(hide yes)
			)
		)
		(property "Voltage" ""
			(at 255.27 36.83 0)
			(effects
				(font
					(size 1.27 1.27)
				)
				(justify left bottom)
				(hide yes)
			)
		)
		(property "Dielectric" ""
			(at 257.81 36.83 0)
			(effects
				(font
					(size 1.27 1.27)
				)
				(justify left bottom)
				(hide yes)
			)
		)
		(pin "1"
		)
		(pin "2"
		)
		(instances
			(project "artix-dc-scm"
				(path ""
					(reference "C99")
					(unit 1)
				)
			)
		)
	)
	(symbol
		(lib_id "antmicropower:GND")
		(at 218.44 71.12 0)
		(unit 1)
		(exclude_from_sim no)
		(in_bom yes)
		(on_board yes)
		(dnp no)
		(property "Reference" "#PWR0244"
			(at 218.44 77.47 0)
			(effects
				(font
					(size 1.27 1.27)
				)
				(hide yes)
			)
		)
		(property "Value" "GND"
			(at 218.44 74.93 0)
			(effects
				(font
					(size 1.27 1.27)
				)
			)
		)
		(property "Footprint" ""
			(at 218.44 71.12 0)
			(effects
				(font
					(size 1.27 1.27)
				)
				(hide yes)
			)
		)
		(property "Datasheet" ""
			(at 218.44 71.12 0)
			(effects
				(font
					(size 1.27 1.27)
				)
				(hide yes)
			)
		)
		(property "Description" ""
			(at 218.44 71.12 0)
			(effects
				(font
					(size 1.27 1.27)
				)
				(hide yes)
			)
		)
		(property "Author" "Antmicro"
			(at 227.33 78.74 0)
			(effects
				(font
					(size 1.27 1.27)
					(thickness 0.15)
				)
				(justify left bottom)
				(hide yes)
			)
		)
		(property "License" "Apache-2.0"
			(at 227.33 81.28 0)
			(effects
				(font
					(size 1.27 1.27)
					(thickness 0.15)
				)
				(justify left bottom)
				(hide yes)
			)
		)
		(pin "1"
		)
		(instances
			(project "artix-dc-scm"
				(path ""
					(reference "#PWR0244")
					(unit 1)
				)
			)
		)
	)
	(symbol
		(lib_id "antmicroFPGAChips:XC7A100T-FGG484")
		(at 252.73 85.09 0)
		(unit 2)
		(exclude_from_sim no)
		(in_bom yes)
		(on_board yes)
		(dnp no)
		(property "Reference" "U14"
			(at 284.48 74.93 0)
			(effects
				(font
					(size 1.27 1.27)
					(thickness 0.15)
				)
			)
		)
		(property "Value" "XC7A100T-FGG484"
			(at 284.48 77.47 0)
			(effects
				(font
					(size 1.27 1.27)
					(thickness 0.15)
				)
			)
		)
		(property "Footprint" "antmicro-footprints:BGA-484_23x23mm_Layout22x22_P1mm_FGG484"
			(at 308.61 92.71 0)
			(effects
				(font
					(size 1.27 1.27)
					(thickness 0.15)
				)
				(justify left bottom)
				(hide yes)
			)
		)
		(property "Datasheet" "https://docs.xilinx.com/v/u/en-US/ds181_Artix_7_Data_Sheet"
			(at 308.61 95.25 0)
			(effects
				(font
					(size 1.27 1.27)
					(thickness 0.15)
				)
				(justify left bottom)
				(hide yes)
			)
		)
		(property "Description" "Artix-7 Field Programmable Gate Array IC 210 324-LFBGA, CSPBGA"
			(at 252.73 85.09 0)
			(effects
				(font
					(size 1.27 1.27)
				)
				(hide yes)
			)
		)
		(property "MPN" "XC7A100T-FGG484"
			(at 308.61 97.79 0)
			(effects
				(font
					(size 1.27 1.27)
					(thickness 0.15)
				)
				(justify left bottom)
				(hide yes)
			)
		)
		(property "Manufacturer" "AMD-Xilinx"
			(at 308.61 100.33 0)
			(effects
				(font
					(size 1.27 1.27)
					(thickness 0.15)
				)
				(justify left bottom)
				(hide yes)
			)
		)
		(property "Author" "Antmicro"
			(at 308.61 102.87 0)
			(effects
				(font
					(size 1.27 1.27)
					(thickness 0.15)
				)
				(justify left bottom)
				(hide yes)
			)
		)
		(property "License" "Apache-2.0"
			(at 308.61 105.41 0)
			(effects
				(font
					(size 1.27 1.27)
					(thickness 0.15)
				)
				(justify left bottom)
				(hide yes)
			)
		)
		(pin "AA10"
		)
		(pin "AA11"
		)
		(pin "AA13"
		)
		(pin "AA14"
		)
		(pin "AA15"
		)
		(pin "AA16"
		)
		(pin "AA17"
		)
		(pin "AA9"
		)
		(pin "AB10"
		)
		(pin "AB11"
		)
		(pin "AB12"
		)
		(pin "AB13"
		)
		(pin "AB14"
		)
		(pin "AB15"
		)
		(pin "AB16"
		)
		(pin "AB17"
		)
		(pin "T14"
		)
		(pin "T15"
		)
		(pin "T16"
		)
		(pin "U15"
		)
		(pin "U16"
		)
		(pin "V10"
		)
		(pin "V13"
		)
		(pin "V14"
		)
		(pin "V15"
		)
		(pin "V16"
		)
		(pin "W10"
		)
		(pin "W11"
		)
		(pin "W12"
		)
		(pin "W13"
		)
		(pin "W14"
		)
		(pin "W15"
		)
		(pin "W16"
		)
		(pin "Y10"
		)
		(pin "Y11"
		)
		(pin "Y12"
		)
		(pin "Y13"
		)
		(pin "Y14"
		)
		(pin "Y16"
		)
		(pin "Y17"
		)
		(pin "AA18"
		)
		(pin "AA19"
		)
		(pin "AA20"
		)
		(pin "AA21"
		)
		(pin "AB18"
		)
		(pin "AB20"
		)
		(pin "AB21"
		)
		(pin "AB22"
		)
		(pin "M14"
		)
		(pin "N13"
		)
		(pin "N14"
		)
		(pin "N15"
		)
		(pin "N17"
		)
		(pin "P14"
		)
		(pin "P15"
		)
		(pin "P16"
		)
		(pin "P17"
		)
		(pin "P18"
		)
		(pin "P19"
		)
		(pin "P20"
		)
		(pin "P21"
		)
		(pin "P22"
		)
		(pin "R14"
		)
		(pin "R15"
		)
		(pin "R16"
		)
		(pin "R17"
		)
		(pin "R18"
		)
		(pin "R19"
		)
		(pin "R21"
		)
		(pin "R22"
		)
		(pin "T18"
		)
		(pin "T19"
		)
		(pin "T20"
		)
		(pin "T21"
		)
		(pin "T22"
		)
		(pin "U17"
		)
		(pin "U18"
		)
		(pin "U19"
		)
		(pin "U20"
		)
		(pin "U21"
		)
		(pin "U22"
		)
		(pin "V17"
		)
		(pin "V18"
		)
		(pin "V19"
		)
		(pin "V20"
		)
		(pin "V22"
		)
		(pin "W17"
		)
		(pin "W19"
		)
		(pin "W20"
		)
		(pin "W21"
		)
		(pin "W22"
		)
		(pin "Y18"
		)
		(pin "Y19"
		)
		(pin "Y20"
		)
		(pin "Y21"
		)
		(pin "Y22"
		)
		(pin "G13"
		)
		(pin "G15"
		)
		(pin "G16"
		)
		(pin "G17"
		)
		(pin "G18"
		)
		(pin "G19"
		)
		(pin "G20"
		)
		(pin "H13"
		)
		(pin "H14"
		)
		(pin "H15"
		)
		(pin "H16"
		)
		(pin "H17"
		)
		(pin "H18"
		)
		(pin "H19"
		)
		(pin "H20"
		)
		(pin "H22"
		)
		(pin "J13"
		)
		(pin "J14"
		)
		(pin "J15"
		)
		(pin "J16"
		)
		(pin "J17"
		)
		(pin "J19"
		)
		(pin "J20"
		)
		(pin "J21"
		)
		(pin "J22"
		)
		(pin "K13"
		)
		(pin "K14"
		)
		(pin "K16"
		)
		(pin "K17"
		)
		(pin "K18"
		)
		(pin "K19"
		)
		(pin "K20"
		)
		(pin "K21"
		)
		(pin "K22"
		)
		(pin "L13"
		)
		(pin "L14"
		)
		(pin "L15"
		)
		(pin "L16"
		)
		(pin "L17"
		)
		(pin "L18"
		)
		(pin "L19"
		)
		(pin "L20"
		)
		(pin "L21"
		)
		(pin "M13"
		)
		(pin "M15"
		)
		(pin "M16"
		)
		(pin "M17"
		)
		(pin "M18"
		)
		(pin "M20"
		)
		(pin "M21"
		)
		(pin "M22"
		)
		(pin "N18"
		)
		(pin "N19"
		)
		(pin "N20"
		)
		(pin "N21"
		)
		(pin "N22"
		)
		(pin "A13"
		)
		(pin "A14"
		)
		(pin "A15"
		)
		(pin "A16"
		)
		(pin "A17"
		)
		(pin "A18"
		)
		(pin "A19"
		)
		(pin "A20"
		)
		(pin "A21"
		)
		(pin "B13"
		)
		(pin "B14"
		)
		(pin "B15"
		)
		(pin "B16"
		)
		(pin "B17"
		)
		(pin "B18"
		)
		(pin "B20"
		)
		(pin "B21"
		)
		(pin "B22"
		)
		(pin "C13"
		)
		(pin "C14"
		)
		(pin "C15"
		)
		(pin "C17"
		)
		(pin "C18"
		)
		(pin "C19"
		)
		(pin "C20"
		)
		(pin "C21"
		)
		(pin "C22"
		)
		(pin "D14"
		)
		(pin "D15"
		)
		(pin "D16"
		)
		(pin "D17"
		)
		(pin "D18"
		)
		(pin "D19"
		)
		(pin "D20"
		)
		(pin "D21"
		)
		(pin "D22"
		)
		(pin "E13"
		)
		(pin "E14"
		)
		(pin "E15"
		)
		(pin "E16"
		)
		(pin "E17"
		)
		(pin "E18"
		)
		(pin "E19"
		)
		(pin "E21"
		)
		(pin "E22"
		)
		(pin "F13"
		)
		(pin "F14"
		)
		(pin "F15"
		)
		(pin "F16"
		)
		(pin "F18"
		)
		(pin "F19"
		)
		(pin "F20"
		)
		(pin "F21"
		)
		(pin "F22"
		)
		(pin "G21"
		)
		(pin "G22"
		)
		(pin "AA1"
		)
		(pin "AA3"
		)
		(pin "AA4"
		)
		(pin "AA5"
		)
		(pin "AA6"
		)
		(pin "AA7"
		)
		(pin "AA8"
		)
		(pin "AB1"
		)
		(pin "AB2"
		)
		(pin "AB3"
		)
		(pin "AB4"
		)
		(pin "AB5"
		)
		(pin "AB6"
		)
		(pin "AB7"
		)
		(pin "AB8"
		)
		(pin "R2"
		)
		(pin "R3"
		)
		(pin "R4"
		)
		(pin "R5"
		)
		(pin "R6"
		)
		(pin "T1"
		)
		(pin "T2"
		)
		(pin "T3"
		)
		(pin "T4"
		)
		(pin "T5"
		)
		(pin "T6"
		)
		(pin "U1"
		)
		(pin "U2"
		)
		(pin "U3"
		)
		(pin "U5"
		)
		(pin "U6"
		)
		(pin "U7"
		)
		(pin "V2"
		)
		(pin "V3"
		)
		(pin "V4"
		)
		(pin "V5"
		)
		(pin "V6"
		)
		(pin "V7"
		)
		(pin "V8"
		)
		(pin "V9"
		)
		(pin "W1"
		)
		(pin "W2"
		)
		(pin "W3"
		)
		(pin "W4"
		)
		(pin "W5"
		)
		(pin "W6"
		)
		(pin "W7"
		)
		(pin "W9"
		)
		(pin "Y1"
		)
		(pin "Y2"
		)
		(pin "Y3"
		)
		(pin "Y4"
		)
		(pin "Y6"
		)
		(pin "Y7"
		)
		(pin "Y8"
		)
		(pin "Y9"
		)
		(pin "A1"
		)
		(pin "B1"
		)
		(pin "B2"
		)
		(pin "C1"
		)
		(pin "C2"
		)
		(pin "D1"
		)
		(pin "D2"
		)
		(pin "E1"
		)
		(pin "E2"
		)
		(pin "E3"
		)
		(pin "F1"
		)
		(pin "F2"
		)
		(pin "F3"
		)
		(pin "F4"
		)
		(pin "G1"
		)
		(pin "G2"
		)
		(pin "G3"
		)
		(pin "G4"
		)
		(pin "H2"
		)
		(pin "H3"
		)
		(pin "H4"
		)
		(pin "H5"
		)
		(pin "H6"
		)
		(pin "J1"
		)
		(pin "J2"
		)
		(pin "J3"
		)
		(pin "J4"
		)
		(pin "J5"
		)
		(pin "J6"
		)
		(pin "K1"
		)
		(pin "K2"
		)
		(pin "K3"
		)
		(pin "K4"
		)
		(pin "K6"
		)
		(pin "L1"
		)
		(pin "L3"
		)
		(pin "L4"
		)
		(pin "L5"
		)
		(pin "L6"
		)
		(pin "M1"
		)
		(pin "M2"
		)
		(pin "M3"
		)
		(pin "M4"
		)
		(pin "M5"
		)
		(pin "M6"
		)
		(pin "N1"
		)
		(pin "N2"
		)
		(pin "N3"
		)
		(pin "N4"
		)
		(pin "N5"
		)
		(pin "P1"
		)
		(pin "P2"
		)
		(pin "P4"
		)
		(pin "P5"
		)
		(pin "P6"
		)
		(pin "R1"
		)
		(pin "F12"
		)
		(pin "G11"
		)
		(pin "L10"
		)
		(pin "L12"
		)
		(pin "L9"
		)
		(pin "M10"
		)
		(pin "M9"
		)
		(pin "N10"
		)
		(pin "N12"
		)
		(pin "N9"
		)
		(pin "R13"
		)
		(pin "T12"
		)
		(pin "T13"
		)
		(pin "U10"
		)
		(pin "U11"
		)
		(pin "U12"
		)
		(pin "U13"
		)
		(pin "U8"
		)
		(pin "U9"
		)
		(pin "V12"
		)
		(pin "A10"
		)
		(pin "A4"
		)
		(pin "A6"
		)
		(pin "A8"
		)
		(pin "B10"
		)
		(pin "B11"
		)
		(pin "B4"
		)
		(pin "B5"
		)
		(pin "B6"
		)
		(pin "B7"
		)
		(pin "B8"
		)
		(pin "B9"
		)
		(pin "C11"
		)
		(pin "C4"
		)
		(pin "C5"
		)
		(pin "C7"
		)
		(pin "C8"
		)
		(pin "C9"
		)
		(pin "D10"
		)
		(pin "D11"
		)
		(pin "D5"
		)
		(pin "D6"
		)
		(pin "D7"
		)
		(pin "D9"
		)
		(pin "E10"
		)
		(pin "E6"
		)
		(pin "E8"
		)
		(pin "F10"
		)
		(pin "F6"
		)
		(pin "F7"
		)
		(pin "F8"
		)
		(pin "F9"
		)
		(pin "A11"
		)
		(pin "A12"
		)
		(pin "A2"
		)
		(pin "A22"
		)
		(pin "A3"
		)
		(pin "A5"
		)
		(pin "A7"
		)
		(pin "A9"
		)
		(pin "AA12"
		)
		(pin "AA2"
		)
		(pin "AA22"
		)
		(pin "AB19"
		)
		(pin "AB9"
		)
		(pin "B12"
		)
		(pin "B19"
		)
		(pin "B3"
		)
		(pin "C10"
		)
		(pin "C12"
		)
		(pin "C16"
		)
		(pin "C3"
		)
		(pin "C6"
		)
		(pin "D12"
		)
		(pin "D13"
		)
		(pin "D3"
		)
		(pin "D4"
		)
		(pin "D8"
		)
		(pin "E11"
		)
		(pin "E12"
		)
		(pin "E20"
		)
		(pin "E4"
		)
		(pin "E5"
		)
		(pin "E7"
		)
		(pin "E9"
		)
		(pin "F11"
		)
		(pin "F17"
		)
		(pin "F5"
		)
		(pin "G10"
		)
		(pin "G12"
		)
		(pin "G14"
		)
		(pin "G5"
		)
		(pin "G6"
		)
		(pin "G7"
		)
		(pin "G8"
		)
		(pin "G9"
		)
		(pin "H1"
		)
		(pin "H10"
		)
		(pin "H11"
		)
		(pin "H12"
		)
		(pin "H21"
		)
		(pin "H7"
		)
		(pin "H8"
		)
		(pin "H9"
		)
		(pin "J10"
		)
		(pin "J11"
		)
		(pin "J12"
		)
		(pin "J18"
		)
		(pin "J7"
		)
		(pin "J8"
		)
		(pin "J9"
		)
		(pin "K10"
		)
		(pin "K11"
		)
		(pin "K12"
		)
		(pin "K15"
		)
		(pin "K5"
		)
		(pin "K7"
		)
		(pin "K8"
		)
		(pin "K9"
		)
		(pin "L11"
		)
		(pin "L2"
		)
		(pin "L22"
		)
		(pin "L7"
		)
		(pin "L8"
		)
		(pin "M11"
		)
		(pin "M12"
		)
		(pin "M19"
		)
		(pin "M7"
		)
		(pin "M8"
		)
		(pin "N11"
		)
		(pin "N16"
		)
		(pin "N6"
		)
		(pin "N7"
		)
		(pin "N8"
		)
		(pin "P10"
		)
		(pin "P11"
		)
		(pin "P12"
		)
		(pin "P13"
		)
		(pin "P3"
		)
		(pin "P7"
		)
		(pin "P8"
		)
		(pin "P9"
		)
		(pin "R10"
		)
		(pin "R11"
		)
		(pin "R12"
		)
		(pin "R20"
		)
		(pin "R7"
		)
		(pin "R8"
		)
		(pin "R9"
		)
		(pin "T10"
		)
		(pin "T11"
		)
		(pin "T17"
		)
		(pin "T7"
		)
		(pin "T8"
		)
		(pin "T9"
		)
		(pin "U14"
		)
		(pin "U4"
		)
		(pin "V1"
		)
		(pin "V11"
		)
		(pin "V21"
		)
		(pin "W18"
		)
		(pin "W8"
		)
		(pin "Y15"
		)
		(pin "Y5"
		)
		(instances
			(project "artix-dc-scm"
				(path ""
					(reference "U14")
					(unit 2)
				)
			)
		)
	)
	(symbol
		(lib_id "antmicropower:GND")
		(at 154.94 55.88 0)
		(mirror y)
		(unit 1)
		(exclude_from_sim no)
		(in_bom yes)
		(on_board yes)
		(dnp no)
		(property "Reference" "#PWR02"
			(at 154.94 62.23 0)
			(effects
				(font
					(size 1.27 1.27)
				)
				(hide yes)
			)
		)
		(property "Value" "GND"
			(at 154.94 59.69 0)
			(effects
				(font
					(size 1.27 1.27)
				)
			)
		)
		(property "Footprint" ""
			(at 154.94 55.88 0)
			(effects
				(font
					(size 1.27 1.27)
				)
				(hide yes)
			)
		)
		(property "Datasheet" ""
			(at 154.94 55.88 0)
			(effects
				(font
					(size 1.27 1.27)
				)
				(hide yes)
			)
		)
		(property "Description" ""
			(at 154.94 55.88 0)
			(effects
				(font
					(size 1.27 1.27)
				)
				(hide yes)
			)
		)
		(property "Author" "Antmicro"
			(at 146.05 63.5 0)
			(effects
				(font
					(size 1.27 1.27)
					(thickness 0.15)
				)
				(justify left bottom)
				(hide yes)
			)
		)
		(property "License" "Apache-2.0"
			(at 146.05 66.04 0)
			(effects
				(font
					(size 1.27 1.27)
					(thickness 0.15)
				)
				(justify left bottom)
				(hide yes)
			)
		)
		(pin "1"
		)
		(instances
			(project "artix-dc-scm"
				(path ""
					(reference "#PWR02")
					(unit 1)
				)
			)
		)
	)
	(symbol
		(lib_id "antmicroCapacitors0402:C_470n_0402")
		(at 154.94 69.85 270)
		(mirror x)
		(unit 1)
		(exclude_from_sim no)
		(in_bom yes)
		(on_board yes)
		(dnp no)
		(property "Reference" "C118"
			(at 154.305 65.405 90)
			(effects
				(font
					(size 1.27 1.27)
				)
				(justify right)
			)
		)
		(property "Value" "C_470n_0402"
			(at 144.78 49.53 0)
			(effects
				(font
					(size 1.27 1.27)
					(thickness 0.15)
				)
				(justify left bottom)
				(hide yes)
			)
		)
		(property "Footprint" "antmicro-footprints:C_0402_1005Metric"
			(at 142.24 49.53 0)
			(effects
				(font
					(size 1.27 1.27)
					(thickness 0.15)
				)
				(justify left bottom)
				(hide yes)
			)
		)
		(property "Datasheet" "https://product.tdk.com/en/search/capacitor/ceramic/mlcc/info?part_no=C1005X5R1E474M050BB"
			(at 139.7 49.53 0)
			(effects
				(font
					(size 1.27 1.27)
					(thickness 0.15)
				)
				(justify left bottom)
				(hide yes)
			)
		)
		(property "Description" "SMD Multilayer Ceramic Capacitor, 0.47 µF, 25 V, 0402 [1005 Metric], ± 20%, X5R, C"
			(at 154.94 69.85 0)
			(effects
				(font
					(size 1.27 1.27)
				)
				(hide yes)
			)
		)
		(property "Manufacturer" "TDK"
			(at 134.62 49.53 0)
			(effects
				(font
					(size 1.27 1.27)
					(thickness 0.15)
				)
				(justify left bottom)
				(hide yes)
			)
		)
		(property "MPN" "C1005X5R1E474M050BB"
			(at 137.16 49.53 0)
			(effects
				(font
					(size 1.27 1.27)
					(thickness 0.15)
				)
				(justify left bottom)
				(hide yes)
			)
		)
		(property "Val" "470n"
			(at 154.305 69.215 90)
			(effects
				(font
					(size 1.27 1.27)
					(thickness 0.15)
				)
				(justify right)
			)
		)
		(property "License" "Apache-2.0"
			(at 132.08 49.53 0)
			(effects
				(font
					(size 1.27 1.27)
					(thickness 0.15)
				)
				(justify left bottom)
				(hide yes)
			)
		)
		(property "Author" "Antmicro"
			(at 129.54 49.53 0)
			(effects
				(font
					(size 1.27 1.27)
					(thickness 0.15)
				)
				(justify left bottom)
				(hide yes)
			)
		)
		(property "Voltage" ""
			(at 127 49.53 0)
			(effects
				(font
					(size 1.27 1.27)
				)
				(justify left bottom)
				(hide yes)
			)
		)
		(property "Dielectric" ""
			(at 124.46 49.53 0)
			(effects
				(font
					(size 1.27 1.27)
				)
				(justify left bottom)
				(hide yes)
			)
		)
		(property "DNP" ""
			(at 154.94 69.85 0)
			(effects
				(font
					(size 1.27 1.27)
				)
			)
		)
		(pin "1"
		)
		(pin "2"
		)
		(instances
			(project "artix-dc-scm"
				(path ""
					(reference "C118")
					(unit 1)
				)
			)
		)
	)
	(symbol
		(lib_id "antmicroCapacitors0603:C_4u7_0603")
		(at 341.63 55.88 270)
		(mirror x)
		(unit 1)
		(exclude_from_sim no)
		(in_bom yes)
		(on_board yes)
		(dnp no)
		(property "Reference" "C104"
			(at 340.995 51.435 90)
			(effects
				(font
					(size 1.27 1.27)
				)
				(justify right)
			)
		)
		(property "Value" "C_4u7_0603"
			(at 331.47 35.56 0)
			(effects
				(font
					(size 1.27 1.27)
					(thickness 0.15)
				)
				(justify left bottom)
				(hide yes)
			)
		)
		(property "Footprint" "antmicro-footprints:C_0603_1608Metric"
			(at 328.93 35.56 0)
			(effects
				(font
					(size 1.27 1.27)
					(thickness 0.15)
				)
				(justify left bottom)
				(hide yes)
			)
		)
		(property "Datasheet" "https://product.tdk.com/en/search/capacitor/ceramic/mlcc/info?part_no=C1608X5R1V475M080AC"
			(at 326.39 35.56 0)
			(effects
				(font
					(size 1.27 1.27)
					(thickness 0.15)
				)
				(justify left bottom)
				(hide yes)
			)
		)
		(property "Description" "SMD Multilayer Ceramic Capacitor, 4.7 µF, 35 V, 0603 [1608 Metric], ± 20%, X5R, C"
			(at 341.63 55.88 0)
			(effects
				(font
					(size 1.27 1.27)
				)
				(hide yes)
			)
		)
		(property "Manufacturer" "TDK"
			(at 321.31 35.56 0)
			(effects
				(font
					(size 1.27 1.27)
					(thickness 0.15)
				)
				(justify left bottom)
				(hide yes)
			)
		)
		(property "MPN" "C1608X5R1V475M080AC"
			(at 323.85 35.56 0)
			(effects
				(font
					(size 1.27 1.27)
					(thickness 0.15)
				)
				(justify left bottom)
				(hide yes)
			)
		)
		(property "Val" "4u7"
			(at 340.995 55.245 90)
			(effects
				(font
					(size 1.27 1.27)
					(thickness 0.15)
				)
				(justify right)
			)
		)
		(property "License" "Apache-2.0"
			(at 318.77 35.56 0)
			(effects
				(font
					(size 1.27 1.27)
					(thickness 0.15)
				)
				(justify left bottom)
				(hide yes)
			)
		)
		(property "Author" "Antmicro"
			(at 316.23 35.56 0)
			(effects
				(font
					(size 1.27 1.27)
					(thickness 0.15)
				)
				(justify left bottom)
				(hide yes)
			)
		)
		(property "Voltage" ""
			(at 313.69 35.56 0)
			(effects
				(font
					(size 1.27 1.27)
				)
				(justify left bottom)
				(hide yes)
			)
		)
		(property "Dielectric" ""
			(at 311.15 35.56 0)
			(effects
				(font
					(size 1.27 1.27)
				)
				(justify left bottom)
				(hide yes)
			)
		)
		(property "DNP" ""
			(at 341.63 55.88 0)
			(effects
				(font
					(size 1.27 1.27)
				)
			)
		)
		(pin "1"
		)
		(pin "2"
		)
		(instances
			(project "artix-dc-scm"
				(path ""
					(reference "C104")
					(unit 1)
				)
			)
		)
	)
	(symbol
		(lib_id "antmicroCapacitorsmisc:C_47u_1210")
		(at 218.44 57.15 90)
		(unit 1)
		(exclude_from_sim no)
		(in_bom yes)
		(on_board yes)
		(dnp no)
		(property "Reference" "C93"
			(at 219.075 52.705 90)
			(effects
				(font
					(size 1.27 1.27)
				)
				(justify right)
			)
		)
		(property "Value" "C_47u_1210"
			(at 228.6 36.83 0)
			(effects
				(font
					(size 1.27 1.27)
					(thickness 0.15)
				)
				(justify left bottom)
				(hide yes)
			)
		)
		(property "Footprint" "antmicro-footprints:C_1210_3225Metric"
			(at 231.14 36.83 0)
			(effects
				(font
					(size 1.27 1.27)
					(thickness 0.15)
				)
				(justify left bottom)
				(hide yes)
			)
		)
		(property "Datasheet" "https://www.kemet.com/en/us/capacitors/product/C1210C476K8RACTU.html"
			(at 233.68 36.83 0)
			(effects
				(font
					(size 1.27 1.27)
					(thickness 0.15)
				)
				(justify left bottom)
				(hide yes)
			)
		)
		(property "Description" "SMD Multilayer Ceramic Capacitor, 47 µF, 10 V, 1210 [3225 Metric], ± 10%, X7R, C Series KEMET"
			(at 218.44 57.15 0)
			(effects
				(font
					(size 1.27 1.27)
				)
				(hide yes)
			)
		)
		(property "Manufacturer" "KEMET"
			(at 238.76 36.83 0)
			(effects
				(font
					(size 1.27 1.27)
					(thickness 0.15)
				)
				(justify left bottom)
				(hide yes)
			)
		)
		(property "MPN" "C1210C476K8RACTU"
			(at 236.22 36.83 0)
			(effects
				(font
					(size 1.27 1.27)
					(thickness 0.15)
				)
				(justify left bottom)
				(hide yes)
			)
		)
		(property "Val" "47u"
			(at 219.075 56.515 90)
			(effects
				(font
					(size 1.27 1.27)
					(thickness 0.15)
				)
				(justify right)
			)
		)
		(property "License" "Apache-2.0"
			(at 241.3 36.83 0)
			(effects
				(font
					(size 1.27 1.27)
					(thickness 0.15)
				)
				(justify left bottom)
				(hide yes)
			)
		)
		(property "Author" "Antmicro"
			(at 243.84 36.83 0)
			(effects
				(font
					(size 1.27 1.27)
					(thickness 0.15)
				)
				(justify left bottom)
				(hide yes)
			)
		)
		(property "Voltage" ""
			(at 246.38 36.83 0)
			(effects
				(font
					(size 1.27 1.27)
				)
				(justify left bottom)
				(hide yes)
			)
		)
		(property "Dielectric" ""
			(at 248.92 36.83 0)
			(effects
				(font
					(size 1.27 1.27)
				)
				(justify left bottom)
				(hide yes)
			)
		)
		(property "Public" "False"
			(at 251.46 36.83 0)
			(effects
				(font
					(size 1.27 1.27)
				)
				(justify left bottom)
				(hide yes)
			)
		)
		(pin "1"
		)
		(pin "2"
		)
		(instances
			(project "artix-dc-scm"
				(path ""
					(reference "C93")
					(unit 1)
				)
			)
		)
	)
	(symbol
		(lib_id "antmicroCapacitors0402:C_470n_0402")
		(at 50.8 57.15 90)
		(unit 1)
		(exclude_from_sim no)
		(in_bom yes)
		(on_board yes)
		(dnp no)
		(property "Reference" "C119"
			(at 51.435 52.705 90)
			(effects
				(font
					(size 1.27 1.27)
				)
				(justify right)
			)
		)
		(property "Value" "C_470n_0402"
			(at 60.96 36.83 0)
			(effects
				(font
					(size 1.27 1.27)
					(thickness 0.15)
				)
				(justify left bottom)
				(hide yes)
			)
		)
		(property "Footprint" "antmicro-footprints:C_0402_1005Metric"
			(at 63.5 36.83 0)
			(effects
				(font
					(size 1.27 1.27)
					(thickness 0.15)
				)
				(justify left bottom)
				(hide yes)
			)
		)
		(property "Datasheet" "https://product.tdk.com/en/search/capacitor/ceramic/mlcc/info?part_no=C1005X5R1E474M050BB"
			(at 66.04 36.83 0)
			(effects
				(font
					(size 1.27 1.27)
					(thickness 0.15)
				)
				(justify left bottom)
				(hide yes)
			)
		)
		(property "Description" "SMD Multilayer Ceramic Capacitor, 0.47 µF, 25 V, 0402 [1005 Metric], ± 20%, X5R, C"
			(at 50.8 57.15 0)
			(effects
				(font
					(size 1.27 1.27)
				)
				(hide yes)
			)
		)
		(property "Manufacturer" "TDK"
			(at 71.12 36.83 0)
			(effects
				(font
					(size 1.27 1.27)
					(thickness 0.15)
				)
				(justify left bottom)
				(hide yes)
			)
		)
		(property "MPN" "C1005X5R1E474M050BB"
			(at 68.58 36.83 0)
			(effects
				(font
					(size 1.27 1.27)
					(thickness 0.15)
				)
				(justify left bottom)
				(hide yes)
			)
		)
		(property "Val" "470n"
			(at 51.435 56.515 90)
			(effects
				(font
					(size 1.27 1.27)
					(thickness 0.15)
				)
				(justify right)
			)
		)
		(property "License" "Apache-2.0"
			(at 73.66 36.83 0)
			(effects
				(font
					(size 1.27 1.27)
					(thickness 0.15)
				)
				(justify left bottom)
				(hide yes)
			)
		)
		(property "Author" "Antmicro"
			(at 76.2 36.83 0)
			(effects
				(font
					(size 1.27 1.27)
					(thickness 0.15)
				)
				(justify left bottom)
				(hide yes)
			)
		)
		(property "Voltage" ""
			(at 78.74 36.83 0)
			(effects
				(font
					(size 1.27 1.27)
				)
				(justify left bottom)
				(hide yes)
			)
		)
		(property "Dielectric" ""
			(at 81.28 36.83 0)
			(effects
				(font
					(size 1.27 1.27)
				)
				(justify left bottom)
				(hide yes)
			)
		)
		(pin "1"
		)
		(pin "2"
		)
		(instances
			(project "artix-dc-scm"
				(path ""
					(reference "C119")
					(unit 1)
				)
			)
		)
	)
	(symbol
		(lib_id "antmicroCapacitorsmisc:C_47u_1210")
		(at 154.94 55.88 270)
		(mirror x)
		(unit 1)
		(exclude_from_sim no)
		(in_bom yes)
		(on_board yes)
		(dnp no)
		(property "Reference" "C94"
			(at 154.305 51.435 90)
			(effects
				(font
					(size 1.27 1.27)
				)
				(justify right)
			)
		)
		(property "Value" "C_47u_1210"
			(at 144.78 35.56 0)
			(effects
				(font
					(size 1.27 1.27)
					(thickness 0.15)
				)
				(justify left bottom)
				(hide yes)
			)
		)
		(property "Footprint" "antmicro-footprints:C_1210_3225Metric"
			(at 142.24 35.56 0)
			(effects
				(font
					(size 1.27 1.27)
					(thickness 0.15)
				)
				(justify left bottom)
				(hide yes)
			)
		)
		(property "Datasheet" "https://www.kemet.com/en/us/capacitors/product/C1210C476K8RACTU.html"
			(at 139.7 35.56 0)
			(effects
				(font
					(size 1.27 1.27)
					(thickness 0.15)
				)
				(justify left bottom)
				(hide yes)
			)
		)
		(property "Description" "SMD Multilayer Ceramic Capacitor, 47 µF, 10 V, 1210 [3225 Metric], ± 10%, X7R, C Series KEMET"
			(at 154.94 55.88 0)
			(effects
				(font
					(size 1.27 1.27)
				)
				(hide yes)
			)
		)
		(property "Manufacturer" "KEMET"
			(at 134.62 35.56 0)
			(effects
				(font
					(size 1.27 1.27)
					(thickness 0.15)
				)
				(justify left bottom)
				(hide yes)
			)
		)
		(property "MPN" "C1210C476K8RACTU"
			(at 137.16 35.56 0)
			(effects
				(font
					(size 1.27 1.27)
					(thickness 0.15)
				)
				(justify left bottom)
				(hide yes)
			)
		)
		(property "Val" "47u"
			(at 154.305 55.245 90)
			(effects
				(font
					(size 1.27 1.27)
					(thickness 0.15)
				)
				(justify right)
			)
		)
		(property "License" "Apache-2.0"
			(at 132.08 35.56 0)
			(effects
				(font
					(size 1.27 1.27)
					(thickness 0.15)
				)
				(justify left bottom)
				(hide yes)
			)
		)
		(property "Author" "Antmicro"
			(at 129.54 35.56 0)
			(effects
				(font
					(size 1.27 1.27)
					(thickness 0.15)
				)
				(justify left bottom)
				(hide yes)
			)
		)
		(property "Voltage" ""
			(at 127 35.56 0)
			(effects
				(font
					(size 1.27 1.27)
				)
				(justify left bottom)
				(hide yes)
			)
		)
		(property "Dielectric" ""
			(at 124.46 35.56 0)
			(effects
				(font
					(size 1.27 1.27)
				)
				(justify left bottom)
				(hide yes)
			)
		)
		(property "Public" "False"
			(at 121.92 35.56 0)
			(effects
				(font
					(size 1.27 1.27)
				)
				(justify left bottom)
				(hide yes)
			)
		)
		(pin "1"
		)
		(pin "2"
		)
		(instances
			(project "artix-dc-scm"
				(path ""
					(reference "C94")
					(unit 1)
				)
			)
		)
	)
	(symbol
		(lib_id "antmicropower:GND")
		(at 227.33 57.15 0)
		(unit 1)
		(exclude_from_sim no)
		(in_bom yes)
		(on_board yes)
		(dnp no)
		(property "Reference" "#PWR0227"
			(at 227.33 63.5 0)
			(effects
				(font
					(size 1.27 1.27)
				)
				(hide yes)
			)
		)
		(property "Value" "GND"
			(at 227.33 60.96 0)
			(effects
				(font
					(size 1.27 1.27)
				)
			)
		)
		(property "Footprint" ""
			(at 227.33 57.15 0)
			(effects
				(font
					(size 1.27 1.27)
				)
				(hide yes)
			)
		)
		(property "Datasheet" ""
			(at 227.33 57.15 0)
			(effects
				(font
					(size 1.27 1.27)
				)
				(hide yes)
			)
		)
		(property "Description" ""
			(at 227.33 57.15 0)
			(effects
				(font
					(size 1.27 1.27)
				)
				(hide yes)
			)
		)
		(property "Author" "Antmicro"
			(at 236.22 64.77 0)
			(effects
				(font
					(size 1.27 1.27)
					(thickness 0.15)
				)
				(justify left bottom)
				(hide yes)
			)
		)
		(property "License" "Apache-2.0"
			(at 236.22 67.31 0)
			(effects
				(font
					(size 1.27 1.27)
					(thickness 0.15)
				)
				(justify left bottom)
				(hide yes)
			)
		)
		(pin "1"
		)
		(instances
			(project "artix-dc-scm"
				(path ""
					(reference "#PWR0227")
					(unit 1)
				)
			)
		)
	)
	(symbol
		(lib_id "antmicropower:GND")
		(at 50.8 57.15 0)
		(unit 1)
		(exclude_from_sim no)
		(in_bom yes)
		(on_board yes)
		(dnp no)
		(property "Reference" "#PWR0218"
			(at 50.8 63.5 0)
			(effects
				(font
					(size 1.27 1.27)
				)
				(hide yes)
			)
		)
		(property "Value" "GND"
			(at 50.8 60.96 0)
			(effects
				(font
					(size 1.27 1.27)
				)
			)
		)
		(property "Footprint" ""
			(at 50.8 57.15 0)
			(effects
				(font
					(size 1.27 1.27)
				)
				(hide yes)
			)
		)
		(property "Datasheet" ""
			(at 50.8 57.15 0)
			(effects
				(font
					(size 1.27 1.27)
				)
				(hide yes)
			)
		)
		(property "Description" ""
			(at 50.8 57.15 0)
			(effects
				(font
					(size 1.27 1.27)
				)
				(hide yes)
			)
		)
		(property "Author" "Antmicro"
			(at 59.69 64.77 0)
			(effects
				(font
					(size 1.27 1.27)
					(thickness 0.15)
				)
				(justify left bottom)
				(hide yes)
			)
		)
		(property "License" "Apache-2.0"
			(at 59.69 67.31 0)
			(effects
				(font
					(size 1.27 1.27)
					(thickness 0.15)
				)
				(justify left bottom)
				(hide yes)
			)
		)
		(pin "1"
		)
		(instances
			(project "artix-dc-scm"
				(path ""
					(reference "#PWR0218")
					(unit 1)
				)
			)
		)
	)
	(symbol
		(lib_id "antmicropower:GND")
		(at 323.85 69.85 0)
		(mirror y)
		(unit 1)
		(exclude_from_sim no)
		(in_bom yes)
		(on_board yes)
		(dnp no)
		(property "Reference" "#PWR030"
			(at 323.85 76.2 0)
			(effects
				(font
					(size 1.27 1.27)
				)
				(hide yes)
			)
		)
		(property "Value" "GND"
			(at 323.85 73.66 0)
			(effects
				(font
					(size 1.27 1.27)
				)
			)
		)
		(property "Footprint" ""
			(at 323.85 69.85 0)
			(effects
				(font
					(size 1.27 1.27)
				)
				(hide yes)
			)
		)
		(property "Datasheet" ""
			(at 323.85 69.85 0)
			(effects
				(font
					(size 1.27 1.27)
				)
				(hide yes)
			)
		)
		(property "Description" ""
			(at 323.85 69.85 0)
			(effects
				(font
					(size 1.27 1.27)
				)
				(hide yes)
			)
		)
		(property "Author" "Antmicro"
			(at 314.96 77.47 0)
			(effects
				(font
					(size 1.27 1.27)
					(thickness 0.15)
				)
				(justify left bottom)
				(hide yes)
			)
		)
		(property "License" "Apache-2.0"
			(at 314.96 80.01 0)
			(effects
				(font
					(size 1.27 1.27)
					(thickness 0.15)
				)
				(justify left bottom)
				(hide yes)
			)
		)
		(pin "1"
		)
		(instances
			(project "artix-dc-scm"
				(path ""
					(reference "#PWR030")
					(unit 1)
				)
			)
		)
	)
	(symbol
		(lib_id "antmicroCapacitors0402:C_470n_0402")
		(at 323.85 69.85 270)
		(mirror x)
		(unit 1)
		(exclude_from_sim no)
		(in_bom yes)
		(on_board yes)
		(dnp no)
		(property "Reference" "C238"
			(at 323.215 65.405 90)
			(effects
				(font
					(size 1.27 1.27)
				)
				(justify right)
			)
		)
		(property "Value" "C_470n_0402"
			(at 313.69 49.53 0)
			(effects
				(font
					(size 1.27 1.27)
					(thickness 0.15)
				)
				(justify left bottom)
				(hide yes)
			)
		)
		(property "Footprint" "antmicro-footprints:C_0402_1005Metric"
			(at 311.15 49.53 0)
			(effects
				(font
					(size 1.27 1.27)
					(thickness 0.15)
				)
				(justify left bottom)
				(hide yes)
			)
		)
		(property "Datasheet" "https://product.tdk.com/en/search/capacitor/ceramic/mlcc/info?part_no=C1005X5R1E474M050BB"
			(at 308.61 49.53 0)
			(effects
				(font
					(size 1.27 1.27)
					(thickness 0.15)
				)
				(justify left bottom)
				(hide yes)
			)
		)
		(property "Description" "SMD Multilayer Ceramic Capacitor, 0.47 µF, 25 V, 0402 [1005 Metric], ± 20%, X5R, C"
			(at 323.85 69.85 0)
			(effects
				(font
					(size 1.27 1.27)
				)
				(hide yes)
			)
		)
		(property "Manufacturer" "TDK"
			(at 303.53 49.53 0)
			(effects
				(font
					(size 1.27 1.27)
					(thickness 0.15)
				)
				(justify left bottom)
				(hide yes)
			)
		)
		(property "MPN" "C1005X5R1E474M050BB"
			(at 306.07 49.53 0)
			(effects
				(font
					(size 1.27 1.27)
					(thickness 0.15)
				)
				(justify left bottom)
				(hide yes)
			)
		)
		(property "Val" "470n"
			(at 323.215 69.215 90)
			(effects
				(font
					(size 1.27 1.27)
					(thickness 0.15)
				)
				(justify right)
			)
		)
		(property "License" "Apache-2.0"
			(at 300.99 49.53 0)
			(effects
				(font
					(size 1.27 1.27)
					(thickness 0.15)
				)
				(justify left bottom)
				(hide yes)
			)
		)
		(property "Author" "Antmicro"
			(at 298.45 49.53 0)
			(effects
				(font
					(size 1.27 1.27)
					(thickness 0.15)
				)
				(justify left bottom)
				(hide yes)
			)
		)
		(property "Voltage" ""
			(at 295.91 49.53 0)
			(effects
				(font
					(size 1.27 1.27)
				)
				(justify left bottom)
				(hide yes)
			)
		)
		(property "Dielectric" ""
			(at 293.37 49.53 0)
			(effects
				(font
					(size 1.27 1.27)
				)
				(justify left bottom)
				(hide yes)
			)
		)
		(property "DNP" ""
			(at 323.85 69.85 0)
			(effects
				(font
					(size 1.27 1.27)
				)
			)
		)
		(pin "1"
		)
		(pin "2"
		)
		(instances
			(project "artix-dc-scm"
				(path ""
					(reference "C238")
					(unit 1)
				)
			)
		)
	)
	(symbol
		(lib_id "antmicroResistors0402:R_0R_0402")
		(at 129.54 116.84 0)
		(unit 1)
		(exclude_from_sim no)
		(in_bom yes)
		(on_board yes)
		(dnp no)
		(property "Reference" "R161"
			(at 127 115.57 0)
			(effects
				(font
					(size 1.27 1.27)
				)
			)
		)
		(property "Value" "R_0R_0402"
			(at 149.86 129.54 0)
			(effects
				(font
					(size 1.27 1.27)
					(thickness 0.15)
				)
				(justify left bottom)
				(hide yes)
			)
		)
		(property "Footprint" "antmicro-footprints:R_0402_1005Metric"
			(at 149.86 132.08 0)
			(effects
				(font
					(size 1.27 1.27)
					(thickness 0.15)
				)
				(justify left bottom)
				(hide yes)
			)
		)
		(property "Datasheet" "https://industrial.panasonic.com/cdbs/www-data/pdf/RDA0000/AOA0000C301.pdf"
			(at 149.86 134.62 0)
			(effects
				(font
					(size 1.27 1.27)
					(thickness 0.15)
				)
				(justify left bottom)
				(hide yes)
			)
		)
		(property "Description" "SMD Chip Resistor, Jumper, 0 ohm, 100 mW, 0402 [1005 Metric], Thick Film, General Purpose"
			(at 129.54 116.84 0)
			(effects
				(font
					(size 1.27 1.27)
				)
				(hide yes)
			)
		)
		(property "Manufacturer" "Panasonic"
			(at 149.86 139.7 0)
			(effects
				(font
					(size 1.27 1.27)
					(thickness 0.15)
				)
				(justify left bottom)
				(hide yes)
			)
		)
		(property "MPN" "ERJ2GE0R00X"
			(at 149.86 137.16 0)
			(effects
				(font
					(size 1.27 1.27)
					(thickness 0.15)
				)
				(justify left bottom)
				(hide yes)
			)
		)
		(property "Val" "0R"
			(at 134.62 116.84 0)
			(effects
				(font
					(size 1.27 1.27)
					(thickness 0.15)
				)
				(justify left bottom)
			)
		)
		(property "License" "Apache-2.0"
			(at 149.86 142.24 0)
			(effects
				(font
					(size 1.27 1.27)
					(thickness 0.15)
				)
				(justify left bottom)
				(hide yes)
			)
		)
		(property "Author" "Antmicro"
			(at 149.86 144.78 0)
			(effects
				(font
					(size 1.27 1.27)
					(thickness 0.15)
				)
				(justify left bottom)
				(hide yes)
			)
		)
		(property "Tolerance" "~"
			(at 149.86 127 0)
			(effects
				(font
					(size 1.27 1.27)
				)
				(justify left bottom)
				(hide yes)
			)
		)
		(property "Current" "1A"
			(at 149.86 147.32 0)
			(effects
				(font
					(size 1.27 1.27)
					(thickness 0.15)
				)
				(justify left bottom)
				(hide yes)
			)
		)
		(property "DNP" ""
			(at 129.54 116.84 0)
			(effects
				(font
					(size 1.27 1.27)
				)
			)
		)
		(pin "1"
		)
		(pin "2"
		)
		(instances
			(project "artix-dc-scm"
				(path ""
					(reference "R161")
					(unit 1)
				)
			)
		)
	)
	(symbol
		(lib_id "antmicropower:GND")
		(at 137.16 69.85 0)
		(mirror y)
		(unit 1)
		(exclude_from_sim no)
		(in_bom yes)
		(on_board yes)
		(dnp no)
		(property "Reference" "#PWR011"
			(at 137.16 76.2 0)
			(effects
				(font
					(size 1.27 1.27)
				)
				(hide yes)
			)
		)
		(property "Value" "GND"
			(at 137.16 73.66 0)
			(effects
				(font
					(size 1.27 1.27)
				)
			)
		)
		(property "Footprint" ""
			(at 137.16 69.85 0)
			(effects
				(font
					(size 1.27 1.27)
				)
				(hide yes)
			)
		)
		(property "Datasheet" ""
			(at 137.16 69.85 0)
			(effects
				(font
					(size 1.27 1.27)
				)
				(hide yes)
			)
		)
		(property "Description" ""
			(at 137.16 69.85 0)
			(effects
				(font
					(size 1.27 1.27)
				)
				(hide yes)
			)
		)
		(property "Author" "Antmicro"
			(at 128.27 77.47 0)
			(effects
				(font
					(size 1.27 1.27)
					(thickness 0.15)
				)
				(justify left bottom)
				(hide yes)
			)
		)
		(property "License" "Apache-2.0"
			(at 128.27 80.01 0)
			(effects
				(font
					(size 1.27 1.27)
					(thickness 0.15)
				)
				(justify left bottom)
				(hide yes)
			)
		)
		(pin "1"
		)
		(instances
			(project "artix-dc-scm"
				(path ""
					(reference "#PWR011")
					(unit 1)
				)
			)
		)
	)
	(symbol
		(lib_id "antmicropower:GND")
		(at 350.52 69.85 0)
		(mirror y)
		(unit 1)
		(exclude_from_sim no)
		(in_bom yes)
		(on_board yes)
		(dnp no)
		(property "Reference" "#PWR019"
			(at 350.52 76.2 0)
			(effects
				(font
					(size 1.27 1.27)
				)
				(hide yes)
			)
		)
		(property "Value" "GND"
			(at 350.52 73.66 0)
			(effects
				(font
					(size 1.27 1.27)
				)
			)
		)
		(property "Footprint" ""
			(at 350.52 69.85 0)
			(effects
				(font
					(size 1.27 1.27)
				)
				(hide yes)
			)
		)
		(property "Datasheet" ""
			(at 350.52 69.85 0)
			(effects
				(font
					(size 1.27 1.27)
				)
				(hide yes)
			)
		)
		(property "Description" ""
			(at 350.52 69.85 0)
			(effects
				(font
					(size 1.27 1.27)
				)
				(hide yes)
			)
		)
		(property "Author" "Antmicro"
			(at 341.63 77.47 0)
			(effects
				(font
					(size 1.27 1.27)
					(thickness 0.15)
				)
				(justify left bottom)
				(hide yes)
			)
		)
		(property "License" "Apache-2.0"
			(at 341.63 80.01 0)
			(effects
				(font
					(size 1.27 1.27)
					(thickness 0.15)
				)
				(justify left bottom)
				(hide yes)
			)
		)
		(pin "1"
		)
		(instances
			(project "artix-dc-scm"
				(path ""
					(reference "#PWR019")
					(unit 1)
				)
			)
		)
	)
	(symbol
		(lib_id "antmicroCapacitors0402:C_470n_0402")
		(at 128.27 69.85 270)
		(mirror x)
		(unit 1)
		(exclude_from_sim no)
		(in_bom yes)
		(on_board yes)
		(dnp no)
		(property "Reference" "C117"
			(at 127.635 65.405 90)
			(effects
				(font
					(size 1.27 1.27)
				)
				(justify right)
			)
		)
		(property "Value" "C_470n_0402"
			(at 118.11 49.53 0)
			(effects
				(font
					(size 1.27 1.27)
					(thickness 0.15)
				)
				(justify left bottom)
				(hide yes)
			)
		)
		(property "Footprint" "antmicro-footprints:C_0402_1005Metric"
			(at 115.57 49.53 0)
			(effects
				(font
					(size 1.27 1.27)
					(thickness 0.15)
				)
				(justify left bottom)
				(hide yes)
			)
		)
		(property "Datasheet" "https://product.tdk.com/en/search/capacitor/ceramic/mlcc/info?part_no=C1005X5R1E474M050BB"
			(at 113.03 49.53 0)
			(effects
				(font
					(size 1.27 1.27)
					(thickness 0.15)
				)
				(justify left bottom)
				(hide yes)
			)
		)
		(property "Description" "SMD Multilayer Ceramic Capacitor, 0.47 µF, 25 V, 0402 [1005 Metric], ± 20%, X5R, C"
			(at 128.27 69.85 0)
			(effects
				(font
					(size 1.27 1.27)
				)
				(hide yes)
			)
		)
		(property "Manufacturer" "TDK"
			(at 107.95 49.53 0)
			(effects
				(font
					(size 1.27 1.27)
					(thickness 0.15)
				)
				(justify left bottom)
				(hide yes)
			)
		)
		(property "MPN" "C1005X5R1E474M050BB"
			(at 110.49 49.53 0)
			(effects
				(font
					(size 1.27 1.27)
					(thickness 0.15)
				)
				(justify left bottom)
				(hide yes)
			)
		)
		(property "Val" "470n"
			(at 127.635 69.215 90)
			(effects
				(font
					(size 1.27 1.27)
					(thickness 0.15)
				)
				(justify right)
			)
		)
		(property "License" "Apache-2.0"
			(at 105.41 49.53 0)
			(effects
				(font
					(size 1.27 1.27)
					(thickness 0.15)
				)
				(justify left bottom)
				(hide yes)
			)
		)
		(property "Author" "Antmicro"
			(at 102.87 49.53 0)
			(effects
				(font
					(size 1.27 1.27)
					(thickness 0.15)
				)
				(justify left bottom)
				(hide yes)
			)
		)
		(property "Voltage" ""
			(at 100.33 49.53 0)
			(effects
				(font
					(size 1.27 1.27)
				)
				(justify left bottom)
				(hide yes)
			)
		)
		(property "Dielectric" ""
			(at 97.79 49.53 0)
			(effects
				(font
					(size 1.27 1.27)
				)
				(justify left bottom)
				(hide yes)
			)
		)
		(property "DNP" ""
			(at 128.27 69.85 0)
			(effects
				(font
					(size 1.27 1.27)
				)
			)
		)
		(pin "1"
		)
		(pin "2"
		)
		(instances
			(project "artix-dc-scm"
				(path ""
					(reference "C117")
					(unit 1)
				)
			)
		)
	)
	(symbol
		(lib_id "antmicroCapacitors0402:C_470n_0402")
		(at 245.11 57.15 90)
		(unit 1)
		(exclude_from_sim no)
		(in_bom yes)
		(on_board yes)
		(dnp no)
		(property "Reference" "C111"
			(at 245.745 52.705 90)
			(effects
				(font
					(size 1.27 1.27)
				)
				(justify right)
			)
		)
		(property "Value" "C_470n_0402"
			(at 255.27 36.83 0)
			(effects
				(font
					(size 1.27 1.27)
					(thickness 0.15)
				)
				(justify left bottom)
				(hide yes)
			)
		)
		(property "Footprint" "antmicro-footprints:C_0402_1005Metric"
			(at 257.81 36.83 0)
			(effects
				(font
					(size 1.27 1.27)
					(thickness 0.15)
				)
				(justify left bottom)
				(hide yes)
			)
		)
		(property "Datasheet" "https://product.tdk.com/en/search/capacitor/ceramic/mlcc/info?part_no=C1005X5R1E474M050BB"
			(at 260.35 36.83 0)
			(effects
				(font
					(size 1.27 1.27)
					(thickness 0.15)
				)
				(justify left bottom)
				(hide yes)
			)
		)
		(property "Description" "SMD Multilayer Ceramic Capacitor, 0.47 µF, 25 V, 0402 [1005 Metric], ± 20%, X5R, C"
			(at 245.11 57.15 0)
			(effects
				(font
					(size 1.27 1.27)
				)
				(hide yes)
			)
		)
		(property "Manufacturer" "TDK"
			(at 265.43 36.83 0)
			(effects
				(font
					(size 1.27 1.27)
					(thickness 0.15)
				)
				(justify left bottom)
				(hide yes)
			)
		)
		(property "MPN" "C1005X5R1E474M050BB"
			(at 262.89 36.83 0)
			(effects
				(font
					(size 1.27 1.27)
					(thickness 0.15)
				)
				(justify left bottom)
				(hide yes)
			)
		)
		(property "Val" "470n"
			(at 245.745 56.515 90)
			(effects
				(font
					(size 1.27 1.27)
					(thickness 0.15)
				)
				(justify right)
			)
		)
		(property "License" "Apache-2.0"
			(at 267.97 36.83 0)
			(effects
				(font
					(size 1.27 1.27)
					(thickness 0.15)
				)
				(justify left bottom)
				(hide yes)
			)
		)
		(property "Author" "Antmicro"
			(at 270.51 36.83 0)
			(effects
				(font
					(size 1.27 1.27)
					(thickness 0.15)
				)
				(justify left bottom)
				(hide yes)
			)
		)
		(property "Voltage" ""
			(at 273.05 36.83 0)
			(effects
				(font
					(size 1.27 1.27)
				)
				(justify left bottom)
				(hide yes)
			)
		)
		(property "Dielectric" ""
			(at 275.59 36.83 0)
			(effects
				(font
					(size 1.27 1.27)
				)
				(justify left bottom)
				(hide yes)
			)
		)
		(pin "1"
		)
		(pin "2"
		)
		(instances
			(project "artix-dc-scm"
				(path ""
					(reference "C111")
					(unit 1)
				)
			)
		)
	)
	(symbol
		(lib_id "antmicroOscillators:Oscillator_100MHz_AMJMEFB")
		(at 358.14 152.4 0)
		(mirror y)
		(unit 1)
		(exclude_from_sim no)
		(in_bom yes)
		(on_board yes)
		(dnp no)
		(fields_autoplaced yes)
		(property "Reference" "U15"
			(at 348.615 142.24 0)
			(effects
				(font
					(size 1.27 1.27)
				)
			)
		)
		(property "Value" "Oscillator_100MHz_AMJMEFB"
			(at 348.615 144.78 0)
			(effects
				(font
					(size 1.27 1.27)
				)
			)
		)
		(property "Footprint" "antmicro-footprints:Oscillator_SMD_Abracon_AMJM_3.2x2.5mm"
			(at 328.93 160.02 0)
			(effects
				(font
					(size 1.27 1.27)
					(thickness 0.15)
				)
				(justify left bottom)
				(hide yes)
			)
		)
		(property "Datasheet" "https://abracon.com/datasheets/AMJM.pdf"
			(at 328.93 162.56 0)
			(effects
				(font
					(size 1.27 1.27)
					(thickness 0.15)
				)
				(justify left bottom)
				(hide yes)
			)
		)
		(property "Description" "MEMS Oscillator, 100 MHz, SMT, 3.2mm x 2.5mm, 25 ppm, 2.5 V, AMJM"
			(at 358.14 152.4 0)
			(effects
				(font
					(size 1.27 1.27)
				)
				(hide yes)
			)
		)
		(property "MPN" "AMJMEFB-100.0000T"
			(at 328.93 165.1 0)
			(effects
				(font
					(size 1.27 1.27)
					(thickness 0.15)
				)
				(justify left bottom)
				(hide yes)
			)
		)
		(property "Manufacturer" "Abracon"
			(at 328.93 167.64 0)
			(effects
				(font
					(size 1.27 1.27)
					(thickness 0.15)
				)
				(justify left bottom)
				(hide yes)
			)
		)
		(property "Author" "Antmicro"
			(at 328.93 170.18 0)
			(effects
				(font
					(size 1.27 1.27)
					(thickness 0.15)
				)
				(justify left bottom)
				(hide yes)
			)
		)
		(property "License" "Apache-2.0"
			(at 328.93 172.72 0)
			(effects
				(font
					(size 1.27 1.27)
					(thickness 0.15)
				)
				(justify left bottom)
				(hide yes)
			)
		)
		(property "Val" "100 MHz"
			(at 348.615 147.32 0)
			(effects
				(font
					(size 1.27 1.27)
					(thickness 0.15)
				)
			)
		)
		(pin "1"
		)
		(pin "2"
		)
		(pin "3"
		)
		(pin "4"
		)
		(instances
			(project "artix-dc-scm"
				(path ""
					(reference "U15")
					(unit 1)
				)
			)
		)
	)
	(symbol
		(lib_id "antmicroCapacitorsmisc:C_47u_1210")
		(at 33.02 57.15 90)
		(unit 1)
		(exclude_from_sim no)
		(in_bom yes)
		(on_board yes)
		(dnp no)
		(property "Reference" "C95"
			(at 33.655 52.705 90)
			(effects
				(font
					(size 1.27 1.27)
				)
				(justify right)
			)
		)
		(property "Value" "C_47u_1210"
			(at 43.18 36.83 0)
			(effects
				(font
					(size 1.27 1.27)
					(thickness 0.15)
				)
				(justify left bottom)
				(hide yes)
			)
		)
		(property "Footprint" "antmicro-footprints:C_1210_3225Metric"
			(at 45.72 36.83 0)
			(effects
				(font
					(size 1.27 1.27)
					(thickness 0.15)
				)
				(justify left bottom)
				(hide yes)
			)
		)
		(property "Datasheet" "https://www.kemet.com/en/us/capacitors/product/C1210C476K8RACTU.html"
			(at 48.26 36.83 0)
			(effects
				(font
					(size 1.27 1.27)
					(thickness 0.15)
				)
				(justify left bottom)
				(hide yes)
			)
		)
		(property "Description" "SMD Multilayer Ceramic Capacitor, 47 µF, 10 V, 1210 [3225 Metric], ± 10%, X7R, C Series KEMET"
			(at 33.02 57.15 0)
			(effects
				(font
					(size 1.27 1.27)
				)
				(hide yes)
			)
		)
		(property "Manufacturer" "KEMET"
			(at 53.34 36.83 0)
			(effects
				(font
					(size 1.27 1.27)
					(thickness 0.15)
				)
				(justify left bottom)
				(hide yes)
			)
		)
		(property "MPN" "C1210C476K8RACTU"
			(at 50.8 36.83 0)
			(effects
				(font
					(size 1.27 1.27)
					(thickness 0.15)
				)
				(justify left bottom)
				(hide yes)
			)
		)
		(property "Val" "47u"
			(at 33.655 56.515 90)
			(effects
				(font
					(size 1.27 1.27)
					(thickness 0.15)
				)
				(justify right)
			)
		)
		(property "License" "Apache-2.0"
			(at 55.88 36.83 0)
			(effects
				(font
					(size 1.27 1.27)
					(thickness 0.15)
				)
				(justify left bottom)
				(hide yes)
			)
		)
		(property "Author" "Antmicro"
			(at 58.42 36.83 0)
			(effects
				(font
					(size 1.27 1.27)
					(thickness 0.15)
				)
				(justify left bottom)
				(hide yes)
			)
		)
		(property "Voltage" ""
			(at 60.96 36.83 0)
			(effects
				(font
					(size 1.27 1.27)
				)
				(justify left bottom)
				(hide yes)
			)
		)
		(property "Dielectric" ""
			(at 63.5 36.83 0)
			(effects
				(font
					(size 1.27 1.27)
				)
				(justify left bottom)
				(hide yes)
			)
		)
		(property "Public" "False"
			(at 66.04 36.83 0)
			(effects
				(font
					(size 1.27 1.27)
				)
				(justify left bottom)
				(hide yes)
			)
		)
		(pin "1"
		)
		(pin "2"
		)
		(instances
			(project "artix-dc-scm"
				(path ""
					(reference "C95")
					(unit 1)
				)
			)
		)
	)
	(symbol
		(lib_id "antmicroCapacitors0402:C_470n_0402")
		(at 227.33 71.12 90)
		(unit 1)
		(exclude_from_sim no)
		(in_bom yes)
		(on_board yes)
		(dnp no)
		(property "Reference" "C129"
			(at 227.965 66.675 90)
			(effects
				(font
					(size 1.27 1.27)
				)
				(justify right)
			)
		)
		(property "Value" "C_470n_0402"
			(at 237.49 50.8 0)
			(effects
				(font
					(size 1.27 1.27)
					(thickness 0.15)
				)
				(justify left bottom)
				(hide yes)
			)
		)
		(property "Footprint" "antmicro-footprints:C_0402_1005Metric"
			(at 240.03 50.8 0)
			(effects
				(font
					(size 1.27 1.27)
					(thickness 0.15)
				)
				(justify left bottom)
				(hide yes)
			)
		)
		(property "Datasheet" "https://product.tdk.com/en/search/capacitor/ceramic/mlcc/info?part_no=C1005X5R1E474M050BB"
			(at 242.57 50.8 0)
			(effects
				(font
					(size 1.27 1.27)
					(thickness 0.15)
				)
				(justify left bottom)
				(hide yes)
			)
		)
		(property "Description" "SMD Multilayer Ceramic Capacitor, 0.47 µF, 25 V, 0402 [1005 Metric], ± 20%, X5R, C"
			(at 227.33 71.12 0)
			(effects
				(font
					(size 1.27 1.27)
				)
				(hide yes)
			)
		)
		(property "Manufacturer" "TDK"
			(at 247.65 50.8 0)
			(effects
				(font
					(size 1.27 1.27)
					(thickness 0.15)
				)
				(justify left bottom)
				(hide yes)
			)
		)
		(property "MPN" "C1005X5R1E474M050BB"
			(at 245.11 50.8 0)
			(effects
				(font
					(size 1.27 1.27)
					(thickness 0.15)
				)
				(justify left bottom)
				(hide yes)
			)
		)
		(property "Val" "470n"
			(at 227.965 70.485 90)
			(effects
				(font
					(size 1.27 1.27)
					(thickness 0.15)
				)
				(justify right)
			)
		)
		(property "License" "Apache-2.0"
			(at 250.19 50.8 0)
			(effects
				(font
					(size 1.27 1.27)
					(thickness 0.15)
				)
				(justify left bottom)
				(hide yes)
			)
		)
		(property "Author" "Antmicro"
			(at 252.73 50.8 0)
			(effects
				(font
					(size 1.27 1.27)
					(thickness 0.15)
				)
				(justify left bottom)
				(hide yes)
			)
		)
		(property "Voltage" ""
			(at 255.27 50.8 0)
			(effects
				(font
					(size 1.27 1.27)
				)
				(justify left bottom)
				(hide yes)
			)
		)
		(property "Dielectric" ""
			(at 257.81 50.8 0)
			(effects
				(font
					(size 1.27 1.27)
				)
				(justify left bottom)
				(hide yes)
			)
		)
		(pin "1"
		)
		(pin "2"
		)
		(instances
			(project "artix-dc-scm"
				(path ""
					(reference "C129")
					(unit 1)
				)
			)
		)
	)
	(symbol
		(lib_id "antmicropower:GND")
		(at 50.8 71.12 0)
		(unit 1)
		(exclude_from_sim no)
		(in_bom yes)
		(on_board yes)
		(dnp no)
		(property "Reference" "#PWR0215"
			(at 50.8 77.47 0)
			(effects
				(font
					(size 1.27 1.27)
				)
				(hide yes)
			)
		)
		(property "Value" "GND"
			(at 50.8 74.93 0)
			(effects
				(font
					(size 1.27 1.27)
				)
			)
		)
		(property "Footprint" ""
			(at 50.8 71.12 0)
			(effects
				(font
					(size 1.27 1.27)
				)
				(hide yes)
			)
		)
		(property "Datasheet" ""
			(at 50.8 71.12 0)
			(effects
				(font
					(size 1.27 1.27)
				)
				(hide yes)
			)
		)
		(property "Description" ""
			(at 50.8 71.12 0)
			(effects
				(font
					(size 1.27 1.27)
				)
				(hide yes)
			)
		)
		(property "Author" "Antmicro"
			(at 59.69 78.74 0)
			(effects
				(font
					(size 1.27 1.27)
					(thickness 0.15)
				)
				(justify left bottom)
				(hide yes)
			)
		)
		(property "License" "Apache-2.0"
			(at 59.69 81.28 0)
			(effects
				(font
					(size 1.27 1.27)
					(thickness 0.15)
				)
				(justify left bottom)
				(hide yes)
			)
		)
		(pin "1"
		)
		(instances
			(project "artix-dc-scm"
				(path ""
					(reference "#PWR0215")
					(unit 1)
				)
			)
		)
	)
	(symbol
		(lib_id "antmicroCapacitors0402:C_470n_0402")
		(at 350.52 69.85 270)
		(mirror x)
		(unit 1)
		(exclude_from_sim no)
		(in_bom yes)
		(on_board yes)
		(dnp no)
		(property "Reference" "C128"
			(at 349.885 65.405 90)
			(effects
				(font
					(size 1.27 1.27)
				)
				(justify right)
			)
		)
		(property "Value" "C_470n_0402"
			(at 340.36 49.53 0)
			(effects
				(font
					(size 1.27 1.27)
					(thickness 0.15)
				)
				(justify left bottom)
				(hide yes)
			)
		)
		(property "Footprint" "antmicro-footprints:C_0402_1005Metric"
			(at 337.82 49.53 0)
			(effects
				(font
					(size 1.27 1.27)
					(thickness 0.15)
				)
				(justify left bottom)
				(hide yes)
			)
		)
		(property "Datasheet" "https://product.tdk.com/en/search/capacitor/ceramic/mlcc/info?part_no=C1005X5R1E474M050BB"
			(at 335.28 49.53 0)
			(effects
				(font
					(size 1.27 1.27)
					(thickness 0.15)
				)
				(justify left bottom)
				(hide yes)
			)
		)
		(property "Description" "SMD Multilayer Ceramic Capacitor, 0.47 µF, 25 V, 0402 [1005 Metric], ± 20%, X5R, C"
			(at 350.52 69.85 0)
			(effects
				(font
					(size 1.27 1.27)
				)
				(hide yes)
			)
		)
		(property "Manufacturer" "TDK"
			(at 330.2 49.53 0)
			(effects
				(font
					(size 1.27 1.27)
					(thickness 0.15)
				)
				(justify left bottom)
				(hide yes)
			)
		)
		(property "MPN" "C1005X5R1E474M050BB"
			(at 332.74 49.53 0)
			(effects
				(font
					(size 1.27 1.27)
					(thickness 0.15)
				)
				(justify left bottom)
				(hide yes)
			)
		)
		(property "Val" "470n"
			(at 349.885 69.215 90)
			(effects
				(font
					(size 1.27 1.27)
					(thickness 0.15)
				)
				(justify right)
			)
		)
		(property "License" "Apache-2.0"
			(at 327.66 49.53 0)
			(effects
				(font
					(size 1.27 1.27)
					(thickness 0.15)
				)
				(justify left bottom)
				(hide yes)
			)
		)
		(property "Author" "Antmicro"
			(at 325.12 49.53 0)
			(effects
				(font
					(size 1.27 1.27)
					(thickness 0.15)
				)
				(justify left bottom)
				(hide yes)
			)
		)
		(property "Voltage" ""
			(at 322.58 49.53 0)
			(effects
				(font
					(size 1.27 1.27)
				)
				(justify left bottom)
				(hide yes)
			)
		)
		(property "Dielectric" ""
			(at 320.04 49.53 0)
			(effects
				(font
					(size 1.27 1.27)
				)
				(justify left bottom)
				(hide yes)
			)
		)
		(property "DNP" ""
			(at 350.52 69.85 0)
			(effects
				(font
					(size 1.27 1.27)
				)
			)
		)
		(pin "1"
		)
		(pin "2"
		)
		(instances
			(project "artix-dc-scm"
				(path ""
					(reference "C128")
					(unit 1)
				)
			)
		)
	)
	(symbol
		(lib_id "antmicropower:GND")
		(at 33.02 57.15 0)
		(unit 1)
		(exclude_from_sim no)
		(in_bom yes)
		(on_board yes)
		(dnp no)
		(property "Reference" "#PWR0216"
			(at 33.02 63.5 0)
			(effects
				(font
					(size 1.27 1.27)
				)
				(hide yes)
			)
		)
		(property "Value" "GND"
			(at 33.02 60.96 0)
			(effects
				(font
					(size 1.27 1.27)
				)
			)
		)
		(property "Footprint" ""
			(at 33.02 57.15 0)
			(effects
				(font
					(size 1.27 1.27)
				)
				(hide yes)
			)
		)
		(property "Datasheet" ""
			(at 33.02 57.15 0)
			(effects
				(font
					(size 1.27 1.27)
				)
				(hide yes)
			)
		)
		(property "Description" ""
			(at 33.02 57.15 0)
			(effects
				(font
					(size 1.27 1.27)
				)
				(hide yes)
			)
		)
		(property "Author" "Antmicro"
			(at 41.91 64.77 0)
			(effects
				(font
					(size 1.27 1.27)
					(thickness 0.15)
				)
				(justify left bottom)
				(hide yes)
			)
		)
		(property "License" "Apache-2.0"
			(at 41.91 67.31 0)
			(effects
				(font
					(size 1.27 1.27)
					(thickness 0.15)
				)
				(justify left bottom)
				(hide yes)
			)
		)
		(pin "1"
		)
		(instances
			(project "artix-dc-scm"
				(path ""
					(reference "#PWR0216")
					(unit 1)
				)
			)
		)
	)
	(symbol
		(lib_id "antmicroFPGAChips:XC7A100T-FGG484")
		(at 58.42 85.09 0)
		(unit 1)
		(exclude_from_sim no)
		(in_bom yes)
		(on_board yes)
		(dnp no)
		(fields_autoplaced yes)
		(property "Reference" "U14"
			(at 90.17 74.93 0)
			(effects
				(font
					(size 1.27 1.27)
				)
			)
		)
		(property "Value" "XC7A100T-FGG484"
			(at 90.17 77.47 0)
			(effects
				(font
					(size 1.27 1.27)
				)
			)
		)
		(property "Footprint" "antmicro-footprints:BGA-484_23x23mm_Layout22x22_P1mm_FGG484"
			(at 114.3 92.71 0)
			(effects
				(font
					(size 1.27 1.27)
					(thickness 0.15)
				)
				(justify left bottom)
				(hide yes)
			)
		)
		(property "Datasheet" "https://docs.xilinx.com/v/u/en-US/ds181_Artix_7_Data_Sheet"
			(at 114.3 95.25 0)
			(effects
				(font
					(size 1.27 1.27)
					(thickness 0.15)
				)
				(justify left bottom)
				(hide yes)
			)
		)
		(property "Description" "Artix-7 Field Programmable Gate Array IC 210 324-LFBGA, CSPBGA"
			(at 58.42 85.09 0)
			(effects
				(font
					(size 1.27 1.27)
				)
				(hide yes)
			)
		)
		(property "MPN" "XC7A100T-FGG484"
			(at 114.3 97.79 0)
			(effects
				(font
					(size 1.27 1.27)
					(thickness 0.15)
				)
				(justify left bottom)
				(hide yes)
			)
		)
		(property "Manufacturer" "AMD-Xilinx"
			(at 114.3 100.33 0)
			(effects
				(font
					(size 1.27 1.27)
					(thickness 0.15)
				)
				(justify left bottom)
				(hide yes)
			)
		)
		(property "Author" "Antmicro"
			(at 114.3 102.87 0)
			(effects
				(font
					(size 1.27 1.27)
					(thickness 0.15)
				)
				(justify left bottom)
				(hide yes)
			)
		)
		(property "License" "Apache-2.0"
			(at 114.3 105.41 0)
			(effects
				(font
					(size 1.27 1.27)
					(thickness 0.15)
				)
				(justify left bottom)
				(hide yes)
			)
		)
		(pin "AA10"
		)
		(pin "AA11"
		)
		(pin "AA13"
		)
		(pin "AA14"
		)
		(pin "AA15"
		)
		(pin "AA16"
		)
		(pin "AA17"
		)
		(pin "AA9"
		)
		(pin "AB10"
		)
		(pin "AB11"
		)
		(pin "AB12"
		)
		(pin "AB13"
		)
		(pin "AB14"
		)
		(pin "AB15"
		)
		(pin "AB16"
		)
		(pin "AB17"
		)
		(pin "T14"
		)
		(pin "T15"
		)
		(pin "T16"
		)
		(pin "U15"
		)
		(pin "U16"
		)
		(pin "V10"
		)
		(pin "V13"
		)
		(pin "V14"
		)
		(pin "V15"
		)
		(pin "V16"
		)
		(pin "W10"
		)
		(pin "W11"
		)
		(pin "W12"
		)
		(pin "W13"
		)
		(pin "W14"
		)
		(pin "W15"
		)
		(pin "W16"
		)
		(pin "Y10"
		)
		(pin "Y11"
		)
		(pin "Y12"
		)
		(pin "Y13"
		)
		(pin "Y14"
		)
		(pin "Y16"
		)
		(pin "Y17"
		)
		(pin "AA18"
		)
		(pin "AA19"
		)
		(pin "AA20"
		)
		(pin "AA21"
		)
		(pin "AB18"
		)
		(pin "AB20"
		)
		(pin "AB21"
		)
		(pin "AB22"
		)
		(pin "M14"
		)
		(pin "N13"
		)
		(pin "N14"
		)
		(pin "N15"
		)
		(pin "N17"
		)
		(pin "P14"
		)
		(pin "P15"
		)
		(pin "P16"
		)
		(pin "P17"
		)
		(pin "P18"
		)
		(pin "P19"
		)
		(pin "P20"
		)
		(pin "P21"
		)
		(pin "P22"
		)
		(pin "R14"
		)
		(pin "R15"
		)
		(pin "R16"
		)
		(pin "R17"
		)
		(pin "R18"
		)
		(pin "R19"
		)
		(pin "R21"
		)
		(pin "R22"
		)
		(pin "T18"
		)
		(pin "T19"
		)
		(pin "T20"
		)
		(pin "T21"
		)
		(pin "T22"
		)
		(pin "U17"
		)
		(pin "U18"
		)
		(pin "U19"
		)
		(pin "U20"
		)
		(pin "U21"
		)
		(pin "U22"
		)
		(pin "V17"
		)
		(pin "V18"
		)
		(pin "V19"
		)
		(pin "V20"
		)
		(pin "V22"
		)
		(pin "W17"
		)
		(pin "W19"
		)
		(pin "W20"
		)
		(pin "W21"
		)
		(pin "W22"
		)
		(pin "Y18"
		)
		(pin "Y19"
		)
		(pin "Y20"
		)
		(pin "Y21"
		)
		(pin "Y22"
		)
		(pin "G13"
		)
		(pin "G15"
		)
		(pin "G16"
		)
		(pin "G17"
		)
		(pin "G18"
		)
		(pin "G19"
		)
		(pin "G20"
		)
		(pin "H13"
		)
		(pin "H14"
		)
		(pin "H15"
		)
		(pin "H16"
		)
		(pin "H17"
		)
		(pin "H18"
		)
		(pin "H19"
		)
		(pin "H20"
		)
		(pin "H22"
		)
		(pin "J13"
		)
		(pin "J14"
		)
		(pin "J15"
		)
		(pin "J16"
		)
		(pin "J17"
		)
		(pin "J19"
		)
		(pin "J20"
		)
		(pin "J21"
		)
		(pin "J22"
		)
		(pin "K13"
		)
		(pin "K14"
		)
		(pin "K16"
		)
		(pin "K17"
		)
		(pin "K18"
		)
		(pin "K19"
		)
		(pin "K20"
		)
		(pin "K21"
		)
		(pin "K22"
		)
		(pin "L13"
		)
		(pin "L14"
		)
		(pin "L15"
		)
		(pin "L16"
		)
		(pin "L17"
		)
		(pin "L18"
		)
		(pin "L19"
		)
		(pin "L20"
		)
		(pin "L21"
		)
		(pin "M13"
		)
		(pin "M15"
		)
		(pin "M16"
		)
		(pin "M17"
		)
		(pin "M18"
		)
		(pin "M20"
		)
		(pin "M21"
		)
		(pin "M22"
		)
		(pin "N18"
		)
		(pin "N19"
		)
		(pin "N20"
		)
		(pin "N21"
		)
		(pin "N22"
		)
		(pin "A13"
		)
		(pin "A14"
		)
		(pin "A15"
		)
		(pin "A16"
		)
		(pin "A17"
		)
		(pin "A18"
		)
		(pin "A19"
		)
		(pin "A20"
		)
		(pin "A21"
		)
		(pin "B13"
		)
		(pin "B14"
		)
		(pin "B15"
		)
		(pin "B16"
		)
		(pin "B17"
		)
		(pin "B18"
		)
		(pin "B20"
		)
		(pin "B21"
		)
		(pin "B22"
		)
		(pin "C13"
		)
		(pin "C14"
		)
		(pin "C15"
		)
		(pin "C17"
		)
		(pin "C18"
		)
		(pin "C19"
		)
		(pin "C20"
		)
		(pin "C21"
		)
		(pin "C22"
		)
		(pin "D14"
		)
		(pin "D15"
		)
		(pin "D16"
		)
		(pin "D17"
		)
		(pin "D18"
		)
		(pin "D19"
		)
		(pin "D20"
		)
		(pin "D21"
		)
		(pin "D22"
		)
		(pin "E13"
		)
		(pin "E14"
		)
		(pin "E15"
		)
		(pin "E16"
		)
		(pin "E17"
		)
		(pin "E18"
		)
		(pin "E19"
		)
		(pin "E21"
		)
		(pin "E22"
		)
		(pin "F13"
		)
		(pin "F14"
		)
		(pin "F15"
		)
		(pin "F16"
		)
		(pin "F18"
		)
		(pin "F19"
		)
		(pin "F20"
		)
		(pin "F21"
		)
		(pin "F22"
		)
		(pin "G21"
		)
		(pin "G22"
		)
		(pin "AA1"
		)
		(pin "AA3"
		)
		(pin "AA4"
		)
		(pin "AA5"
		)
		(pin "AA6"
		)
		(pin "AA7"
		)
		(pin "AA8"
		)
		(pin "AB1"
		)
		(pin "AB2"
		)
		(pin "AB3"
		)
		(pin "AB4"
		)
		(pin "AB5"
		)
		(pin "AB6"
		)
		(pin "AB7"
		)
		(pin "AB8"
		)
		(pin "R2"
		)
		(pin "R3"
		)
		(pin "R4"
		)
		(pin "R5"
		)
		(pin "R6"
		)
		(pin "T1"
		)
		(pin "T2"
		)
		(pin "T3"
		)
		(pin "T4"
		)
		(pin "T5"
		)
		(pin "T6"
		)
		(pin "U1"
		)
		(pin "U2"
		)
		(pin "U3"
		)
		(pin "U5"
		)
		(pin "U6"
		)
		(pin "U7"
		)
		(pin "V2"
		)
		(pin "V3"
		)
		(pin "V4"
		)
		(pin "V5"
		)
		(pin "V6"
		)
		(pin "V7"
		)
		(pin "V8"
		)
		(pin "V9"
		)
		(pin "W1"
		)
		(pin "W2"
		)
		(pin "W3"
		)
		(pin "W4"
		)
		(pin "W5"
		)
		(pin "W6"
		)
		(pin "W7"
		)
		(pin "W9"
		)
		(pin "Y1"
		)
		(pin "Y2"
		)
		(pin "Y3"
		)
		(pin "Y4"
		)
		(pin "Y6"
		)
		(pin "Y7"
		)
		(pin "Y8"
		)
		(pin "Y9"
		)
		(pin "A1"
		)
		(pin "B1"
		)
		(pin "B2"
		)
		(pin "C1"
		)
		(pin "C2"
		)
		(pin "D1"
		)
		(pin "D2"
		)
		(pin "E1"
		)
		(pin "E2"
		)
		(pin "E3"
		)
		(pin "F1"
		)
		(pin "F2"
		)
		(pin "F3"
		)
		(pin "F4"
		)
		(pin "G1"
		)
		(pin "G2"
		)
		(pin "G3"
		)
		(pin "G4"
		)
		(pin "H2"
		)
		(pin "H3"
		)
		(pin "H4"
		)
		(pin "H5"
		)
		(pin "H6"
		)
		(pin "J1"
		)
		(pin "J2"
		)
		(pin "J3"
		)
		(pin "J4"
		)
		(pin "J5"
		)
		(pin "J6"
		)
		(pin "K1"
		)
		(pin "K2"
		)
		(pin "K3"
		)
		(pin "K4"
		)
		(pin "K6"
		)
		(pin "L1"
		)
		(pin "L3"
		)
		(pin "L4"
		)
		(pin "L5"
		)
		(pin "L6"
		)
		(pin "M1"
		)
		(pin "M2"
		)
		(pin "M3"
		)
		(pin "M4"
		)
		(pin "M5"
		)
		(pin "M6"
		)
		(pin "N1"
		)
		(pin "N2"
		)
		(pin "N3"
		)
		(pin "N4"
		)
		(pin "N5"
		)
		(pin "P1"
		)
		(pin "P2"
		)
		(pin "P4"
		)
		(pin "P5"
		)
		(pin "P6"
		)
		(pin "R1"
		)
		(pin "F12"
		)
		(pin "G11"
		)
		(pin "L10"
		)
		(pin "L12"
		)
		(pin "L9"
		)
		(pin "M10"
		)
		(pin "M9"
		)
		(pin "N10"
		)
		(pin "N12"
		)
		(pin "N9"
		)
		(pin "R13"
		)
		(pin "T12"
		)
		(pin "T13"
		)
		(pin "U10"
		)
		(pin "U11"
		)
		(pin "U12"
		)
		(pin "U13"
		)
		(pin "U8"
		)
		(pin "U9"
		)
		(pin "V12"
		)
		(pin "A10"
		)
		(pin "A4"
		)
		(pin "A6"
		)
		(pin "A8"
		)
		(pin "B10"
		)
		(pin "B11"
		)
		(pin "B4"
		)
		(pin "B5"
		)
		(pin "B6"
		)
		(pin "B7"
		)
		(pin "B8"
		)
		(pin "B9"
		)
		(pin "C11"
		)
		(pin "C4"
		)
		(pin "C5"
		)
		(pin "C7"
		)
		(pin "C8"
		)
		(pin "C9"
		)
		(pin "D10"
		)
		(pin "D11"
		)
		(pin "D5"
		)
		(pin "D6"
		)
		(pin "D7"
		)
		(pin "D9"
		)
		(pin "E10"
		)
		(pin "E6"
		)
		(pin "E8"
		)
		(pin "F10"
		)
		(pin "F6"
		)
		(pin "F7"
		)
		(pin "F8"
		)
		(pin "F9"
		)
		(pin "A11"
		)
		(pin "A12"
		)
		(pin "A2"
		)
		(pin "A22"
		)
		(pin "A3"
		)
		(pin "A5"
		)
		(pin "A7"
		)
		(pin "A9"
		)
		(pin "AA12"
		)
		(pin "AA2"
		)
		(pin "AA22"
		)
		(pin "AB19"
		)
		(pin "AB9"
		)
		(pin "B12"
		)
		(pin "B19"
		)
		(pin "B3"
		)
		(pin "C10"
		)
		(pin "C12"
		)
		(pin "C16"
		)
		(pin "C3"
		)
		(pin "C6"
		)
		(pin "D12"
		)
		(pin "D13"
		)
		(pin "D3"
		)
		(pin "D4"
		)
		(pin "D8"
		)
		(pin "E11"
		)
		(pin "E12"
		)
		(pin "E20"
		)
		(pin "E4"
		)
		(pin "E5"
		)
		(pin "E7"
		)
		(pin "E9"
		)
		(pin "F11"
		)
		(pin "F17"
		)
		(pin "F5"
		)
		(pin "G10"
		)
		(pin "G12"
		)
		(pin "G14"
		)
		(pin "G5"
		)
		(pin "G6"
		)
		(pin "G7"
		)
		(pin "G8"
		)
		(pin "G9"
		)
		(pin "H1"
		)
		(pin "H10"
		)
		(pin "H11"
		)
		(pin "H12"
		)
		(pin "H21"
		)
		(pin "H7"
		)
		(pin "H8"
		)
		(pin "H9"
		)
		(pin "J10"
		)
		(pin "J11"
		)
		(pin "J12"
		)
		(pin "J18"
		)
		(pin "J7"
		)
		(pin "J8"
		)
		(pin "J9"
		)
		(pin "K10"
		)
		(pin "K11"
		)
		(pin "K12"
		)
		(pin "K15"
		)
		(pin "K5"
		)
		(pin "K7"
		)
		(pin "K8"
		)
		(pin "K9"
		)
		(pin "L11"
		)
		(pin "L2"
		)
		(pin "L22"
		)
		(pin "L7"
		)
		(pin "L8"
		)
		(pin "M11"
		)
		(pin "M12"
		)
		(pin "M19"
		)
		(pin "M7"
		)
		(pin "M8"
		)
		(pin "N11"
		)
		(pin "N16"
		)
		(pin "N6"
		)
		(pin "N7"
		)
		(pin "N8"
		)
		(pin "P10"
		)
		(pin "P11"
		)
		(pin "P12"
		)
		(pin "P13"
		)
		(pin "P3"
		)
		(pin "P7"
		)
		(pin "P8"
		)
		(pin "P9"
		)
		(pin "R10"
		)
		(pin "R11"
		)
		(pin "R12"
		)
		(pin "R20"
		)
		(pin "R7"
		)
		(pin "R8"
		)
		(pin "R9"
		)
		(pin "T10"
		)
		(pin "T11"
		)
		(pin "T17"
		)
		(pin "T7"
		)
		(pin "T8"
		)
		(pin "T9"
		)
		(pin "U14"
		)
		(pin "U4"
		)
		(pin "V1"
		)
		(pin "V11"
		)
		(pin "V21"
		)
		(pin "W18"
		)
		(pin "W8"
		)
		(pin "Y15"
		)
		(pin "Y5"
		)
		(instances
			(project "artix-dc-scm"
				(path ""
					(reference "U14")
					(unit 1)
				)
			)
		)
	)
	(symbol
		(lib_id "antmicroCapacitors0402:C_470n_0402")
		(at 50.8 71.12 90)
		(unit 1)
		(exclude_from_sim no)
		(in_bom yes)
		(on_board yes)
		(dnp no)
		(property "Reference" "C131"
			(at 51.435 66.675 90)
			(effects
				(font
					(size 1.27 1.27)
				)
				(justify right)
			)
		)
		(property "Value" "C_470n_0402"
			(at 60.96 50.8 0)
			(effects
				(font
					(size 1.27 1.27)
					(thickness 0.15)
				)
				(justify left bottom)
				(hide yes)
			)
		)
		(property "Footprint" "antmicro-footprints:C_0402_1005Metric"
			(at 63.5 50.8 0)
			(effects
				(font
					(size 1.27 1.27)
					(thickness 0.15)
				)
				(justify left bottom)
				(hide yes)
			)
		)
		(property "Datasheet" "https://product.tdk.com/en/search/capacitor/ceramic/mlcc/info?part_no=C1005X5R1E474M050BB"
			(at 66.04 50.8 0)
			(effects
				(font
					(size 1.27 1.27)
					(thickness 0.15)
				)
				(justify left bottom)
				(hide yes)
			)
		)
		(property "Description" "SMD Multilayer Ceramic Capacitor, 0.47 µF, 25 V, 0402 [1005 Metric], ± 20%, X5R, C"
			(at 50.8 71.12 0)
			(effects
				(font
					(size 1.27 1.27)
				)
				(hide yes)
			)
		)
		(property "Manufacturer" "TDK"
			(at 71.12 50.8 0)
			(effects
				(font
					(size 1.27 1.27)
					(thickness 0.15)
				)
				(justify left bottom)
				(hide yes)
			)
		)
		(property "MPN" "C1005X5R1E474M050BB"
			(at 68.58 50.8 0)
			(effects
				(font
					(size 1.27 1.27)
					(thickness 0.15)
				)
				(justify left bottom)
				(hide yes)
			)
		)
		(property "Val" "470n"
			(at 51.435 70.485 90)
			(effects
				(font
					(size 1.27 1.27)
					(thickness 0.15)
				)
				(justify right)
			)
		)
		(property "License" "Apache-2.0"
			(at 73.66 50.8 0)
			(effects
				(font
					(size 1.27 1.27)
					(thickness 0.15)
				)
				(justify left bottom)
				(hide yes)
			)
		)
		(property "Author" "Antmicro"
			(at 76.2 50.8 0)
			(effects
				(font
					(size 1.27 1.27)
					(thickness 0.15)
				)
				(justify left bottom)
				(hide yes)
			)
		)
		(property "Voltage" ""
			(at 78.74 50.8 0)
			(effects
				(font
					(size 1.27 1.27)
				)
				(justify left bottom)
				(hide yes)
			)
		)
		(property "Dielectric" ""
			(at 81.28 50.8 0)
			(effects
				(font
					(size 1.27 1.27)
				)
				(justify left bottom)
				(hide yes)
			)
		)
		(pin "1"
		)
		(pin "2"
		)
		(instances
			(project "artix-dc-scm"
				(path ""
					(reference "C131")
					(unit 1)
				)
			)
		)
	)
	(symbol
		(lib_id "antmicroCapacitors0402:C_100n_0402")
		(at 365.76 158.75 270)
		(mirror x)
		(unit 1)
		(exclude_from_sim no)
		(in_bom yes)
		(on_board yes)
		(dnp no)
		(property "Reference" "C233"
			(at 365.125 154.305 90)
			(effects
				(font
					(size 1.27 1.27)
				)
				(justify right)
			)
		)
		(property "Value" "C_100n_0402"
			(at 355.6 138.43 0)
			(effects
				(font
					(size 1.27 1.27)
					(thickness 0.15)
				)
				(justify left bottom)
				(hide yes)
			)
		)
		(property "Footprint" "antmicro-footprints:C_0402_1005Metric"
			(at 353.06 138.43 0)
			(effects
				(font
					(size 1.27 1.27)
					(thickness 0.15)
				)
				(justify left bottom)
				(hide yes)
			)
		)
		(property "Datasheet" "https://www.murata.com/products/productdetail?partno=GRM155R61H104KE14%23"
			(at 350.52 138.43 0)
			(effects
				(font
					(size 1.27 1.27)
					(thickness 0.15)
				)
				(justify left bottom)
				(hide yes)
			)
		)
		(property "Description" "SMD Multilayer Ceramic Capacitor, 0.1 µF, 50 V, 0402 [1005 Metric], ± 10%, X5R, GRM Series"
			(at 365.76 158.75 0)
			(effects
				(font
					(size 1.27 1.27)
				)
				(hide yes)
			)
		)
		(property "Manufacturer" "Murata"
			(at 345.44 138.43 0)
			(effects
				(font
					(size 1.27 1.27)
					(thickness 0.15)
				)
				(justify left bottom)
				(hide yes)
			)
		)
		(property "MPN" "GRM155R61H104KE14D"
			(at 347.98 138.43 0)
			(effects
				(font
					(size 1.27 1.27)
					(thickness 0.15)
				)
				(justify left bottom)
				(hide yes)
			)
		)
		(property "Val" "100n"
			(at 365.125 158.115 90)
			(effects
				(font
					(size 1.27 1.27)
					(thickness 0.15)
				)
				(justify right)
			)
		)
		(property "License" "Apache-2.0"
			(at 342.9 138.43 0)
			(effects
				(font
					(size 1.27 1.27)
					(thickness 0.15)
				)
				(justify left bottom)
				(hide yes)
			)
		)
		(property "Author" "Antmicro"
			(at 340.36 138.43 0)
			(effects
				(font
					(size 1.27 1.27)
					(thickness 0.15)
				)
				(justify left bottom)
				(hide yes)
			)
		)
		(property "Voltage" "50V"
			(at 337.82 138.43 0)
			(effects
				(font
					(size 1.27 1.27)
				)
				(justify left bottom)
				(hide yes)
			)
		)
		(property "Dielectric" "X5R"
			(at 335.28 138.43 0)
			(effects
				(font
					(size 1.27 1.27)
				)
				(justify left bottom)
				(hide yes)
			)
		)
		(property "DNP" ""
			(at 365.76 158.75 0)
			(effects
				(font
					(size 1.27 1.27)
				)
			)
		)
		(pin "1"
		)
		(pin "2"
		)
		(instances
			(project "artix-dc-scm"
				(path ""
					(reference "C233")
					(unit 1)
				)
			)
		)
	)
	(symbol
		(lib_id "antmicropower:GND")
		(at 218.44 57.15 0)
		(unit 1)
		(exclude_from_sim no)
		(in_bom yes)
		(on_board yes)
		(dnp no)
		(property "Reference" "#PWR0243"
			(at 218.44 63.5 0)
			(effects
				(font
					(size 1.27 1.27)
				)
				(hide yes)
			)
		)
		(property "Value" "GND"
			(at 218.44 60.96 0)
			(effects
				(font
					(size 1.27 1.27)
				)
			)
		)
		(property "Footprint" ""
			(at 218.44 57.15 0)
			(effects
				(font
					(size 1.27 1.27)
				)
				(hide yes)
			)
		)
		(property "Datasheet" ""
			(at 218.44 57.15 0)
			(effects
				(font
					(size 1.27 1.27)
				)
				(hide yes)
			)
		)
		(property "Description" ""
			(at 218.44 57.15 0)
			(effects
				(font
					(size 1.27 1.27)
				)
				(hide yes)
			)
		)
		(property "Author" "Antmicro"
			(at 227.33 64.77 0)
			(effects
				(font
					(size 1.27 1.27)
					(thickness 0.15)
				)
				(justify left bottom)
				(hide yes)
			)
		)
		(property "License" "Apache-2.0"
			(at 227.33 67.31 0)
			(effects
				(font
					(size 1.27 1.27)
					(thickness 0.15)
				)
				(justify left bottom)
				(hide yes)
			)
		)
		(pin "1"
		)
		(instances
			(project "artix-dc-scm"
				(path ""
					(reference "#PWR0243")
					(unit 1)
				)
			)
		)
	)
	(symbol
		(lib_id "antmicroCapacitors0402:C_470n_0402")
		(at 359.41 69.85 270)
		(mirror x)
		(unit 1)
		(exclude_from_sim no)
		(in_bom yes)
		(on_board yes)
		(dnp no)
		(property "Reference" "C122"
			(at 358.775 65.405 90)
			(effects
				(font
					(size 1.27 1.27)
				)
				(justify right)
			)
		)
		(property "Value" "C_470n_0402"
			(at 349.25 49.53 0)
			(effects
				(font
					(size 1.27 1.27)
					(thickness 0.15)
				)
				(justify left bottom)
				(hide yes)
			)
		)
		(property "Footprint" "antmicro-footprints:C_0402_1005Metric"
			(at 346.71 49.53 0)
			(effects
				(font
					(size 1.27 1.27)
					(thickness 0.15)
				)
				(justify left bottom)
				(hide yes)
			)
		)
		(property "Datasheet" "https://product.tdk.com/en/search/capacitor/ceramic/mlcc/info?part_no=C1005X5R1E474M050BB"
			(at 344.17 49.53 0)
			(effects
				(font
					(size 1.27 1.27)
					(thickness 0.15)
				)
				(justify left bottom)
				(hide yes)
			)
		)
		(property "Description" "SMD Multilayer Ceramic Capacitor, 0.47 µF, 25 V, 0402 [1005 Metric], ± 20%, X5R, C"
			(at 359.41 69.85 0)
			(effects
				(font
					(size 1.27 1.27)
				)
				(hide yes)
			)
		)
		(property "Manufacturer" "TDK"
			(at 339.09 49.53 0)
			(effects
				(font
					(size 1.27 1.27)
					(thickness 0.15)
				)
				(justify left bottom)
				(hide yes)
			)
		)
		(property "MPN" "C1005X5R1E474M050BB"
			(at 341.63 49.53 0)
			(effects
				(font
					(size 1.27 1.27)
					(thickness 0.15)
				)
				(justify left bottom)
				(hide yes)
			)
		)
		(property "Val" "470n"
			(at 358.775 69.215 90)
			(effects
				(font
					(size 1.27 1.27)
					(thickness 0.15)
				)
				(justify right)
			)
		)
		(property "License" "Apache-2.0"
			(at 336.55 49.53 0)
			(effects
				(font
					(size 1.27 1.27)
					(thickness 0.15)
				)
				(justify left bottom)
				(hide yes)
			)
		)
		(property "Author" "Antmicro"
			(at 334.01 49.53 0)
			(effects
				(font
					(size 1.27 1.27)
					(thickness 0.15)
				)
				(justify left bottom)
				(hide yes)
			)
		)
		(property "Voltage" ""
			(at 331.47 49.53 0)
			(effects
				(font
					(size 1.27 1.27)
				)
				(justify left bottom)
				(hide yes)
			)
		)
		(property "Dielectric" ""
			(at 328.93 49.53 0)
			(effects
				(font
					(size 1.27 1.27)
				)
				(justify left bottom)
				(hide yes)
			)
		)
		(property "DNP" ""
			(at 359.41 69.85 0)
			(effects
				(font
					(size 1.27 1.27)
				)
			)
		)
		(pin "1"
		)
		(pin "2"
		)
		(instances
			(project "artix-dc-scm"
				(path ""
					(reference "C122")
					(unit 1)
				)
			)
		)
	)
	(symbol
		(lib_id "antmicropower:GND")
		(at 359.41 158.75 0)
		(mirror y)
		(unit 1)
		(exclude_from_sim no)
		(in_bom yes)
		(on_board yes)
		(dnp no)
		(property "Reference" "#PWR017"
			(at 359.41 165.1 0)
			(effects
				(font
					(size 1.27 1.27)
				)
				(hide yes)
			)
		)
		(property "Value" "GND"
			(at 359.41 162.56 0)
			(effects
				(font
					(size 1.27 1.27)
				)
			)
		)
		(property "Footprint" ""
			(at 359.41 158.75 0)
			(effects
				(font
					(size 1.27 1.27)
				)
				(hide yes)
			)
		)
		(property "Datasheet" ""
			(at 359.41 158.75 0)
			(effects
				(font
					(size 1.27 1.27)
				)
				(hide yes)
			)
		)
		(property "Description" ""
			(at 359.41 158.75 0)
			(effects
				(font
					(size 1.27 1.27)
				)
				(hide yes)
			)
		)
		(property "Author" "Antmicro"
			(at 350.52 166.37 0)
			(effects
				(font
					(size 1.27 1.27)
					(thickness 0.15)
				)
				(justify left bottom)
				(hide yes)
			)
		)
		(property "License" "Apache-2.0"
			(at 350.52 168.91 0)
			(effects
				(font
					(size 1.27 1.27)
					(thickness 0.15)
				)
				(justify left bottom)
				(hide yes)
			)
		)
		(pin "1"
		)
		(instances
			(project "artix-dc-scm"
				(path ""
					(reference "#PWR017")
					(unit 1)
				)
			)
		)
	)
	(symbol
		(lib_id "antmicroCapacitors0402:C_470n_0402")
		(at 341.63 69.85 270)
		(mirror x)
		(unit 1)
		(exclude_from_sim no)
		(in_bom yes)
		(on_board yes)
		(dnp no)
		(property "Reference" "C235"
			(at 340.995 65.405 90)
			(effects
				(font
					(size 1.27 1.27)
				)
				(justify right)
			)
		)
		(property "Value" "C_470n_0402"
			(at 331.47 49.53 0)
			(effects
				(font
					(size 1.27 1.27)
					(thickness 0.15)
				)
				(justify left bottom)
				(hide yes)
			)
		)
		(property "Footprint" "antmicro-footprints:C_0402_1005Metric"
			(at 328.93 49.53 0)
			(effects
				(font
					(size 1.27 1.27)
					(thickness 0.15)
				)
				(justify left bottom)
				(hide yes)
			)
		)
		(property "Datasheet" "https://product.tdk.com/en/search/capacitor/ceramic/mlcc/info?part_no=C1005X5R1E474M050BB"
			(at 326.39 49.53 0)
			(effects
				(font
					(size 1.27 1.27)
					(thickness 0.15)
				)
				(justify left bottom)
				(hide yes)
			)
		)
		(property "Description" "SMD Multilayer Ceramic Capacitor, 0.47 µF, 25 V, 0402 [1005 Metric], ± 20%, X5R, C"
			(at 341.63 69.85 0)
			(effects
				(font
					(size 1.27 1.27)
				)
				(hide yes)
			)
		)
		(property "Manufacturer" "TDK"
			(at 321.31 49.53 0)
			(effects
				(font
					(size 1.27 1.27)
					(thickness 0.15)
				)
				(justify left bottom)
				(hide yes)
			)
		)
		(property "MPN" "C1005X5R1E474M050BB"
			(at 323.85 49.53 0)
			(effects
				(font
					(size 1.27 1.27)
					(thickness 0.15)
				)
				(justify left bottom)
				(hide yes)
			)
		)
		(property "Val" "470n"
			(at 340.995 69.215 90)
			(effects
				(font
					(size 1.27 1.27)
					(thickness 0.15)
				)
				(justify right)
			)
		)
		(property "License" "Apache-2.0"
			(at 318.77 49.53 0)
			(effects
				(font
					(size 1.27 1.27)
					(thickness 0.15)
				)
				(justify left bottom)
				(hide yes)
			)
		)
		(property "Author" "Antmicro"
			(at 316.23 49.53 0)
			(effects
				(font
					(size 1.27 1.27)
					(thickness 0.15)
				)
				(justify left bottom)
				(hide yes)
			)
		)
		(property "Voltage" ""
			(at 313.69 49.53 0)
			(effects
				(font
					(size 1.27 1.27)
				)
				(justify left bottom)
				(hide yes)
			)
		)
		(property "Dielectric" ""
			(at 311.15 49.53 0)
			(effects
				(font
					(size 1.27 1.27)
				)
				(justify left bottom)
				(hide yes)
			)
		)
		(property "DNP" ""
			(at 341.63 69.85 0)
			(effects
				(font
					(size 1.27 1.27)
				)
			)
		)
		(pin "1"
		)
		(pin "2"
		)
		(instances
			(project "artix-dc-scm"
				(path ""
					(reference "C235")
					(unit 1)
				)
			)
		)
	)
	(symbol
		(lib_id "antmicropower:GND")
		(at 154.94 69.85 0)
		(mirror y)
		(unit 1)
		(exclude_from_sim no)
		(in_bom yes)
		(on_board yes)
		(dnp no)
		(property "Reference" "#PWR04"
			(at 154.94 76.2 0)
			(effects
				(font
					(size 1.27 1.27)
				)
				(hide yes)
			)
		)
		(property "Value" "GND"
			(at 154.94 73.66 0)
			(effects
				(font
					(size 1.27 1.27)
				)
			)
		)
		(property "Footprint" ""
			(at 154.94 69.85 0)
			(effects
				(font
					(size 1.27 1.27)
				)
				(hide yes)
			)
		)
		(property "Datasheet" ""
			(at 154.94 69.85 0)
			(effects
				(font
					(size 1.27 1.27)
				)
				(hide yes)
			)
		)
		(property "Description" ""
			(at 154.94 69.85 0)
			(effects
				(font
					(size 1.27 1.27)
				)
				(hide yes)
			)
		)
		(property "Author" "Antmicro"
			(at 146.05 77.47 0)
			(effects
				(font
					(size 1.27 1.27)
					(thickness 0.15)
				)
				(justify left bottom)
				(hide yes)
			)
		)
		(property "License" "Apache-2.0"
			(at 146.05 80.01 0)
			(effects
				(font
					(size 1.27 1.27)
					(thickness 0.15)
				)
				(justify left bottom)
				(hide yes)
			)
		)
		(pin "1"
		)
		(instances
			(project "artix-dc-scm"
				(path ""
					(reference "#PWR04")
					(unit 1)
				)
			)
		)
	)
	(symbol
		(lib_id "antmicropower:GND")
		(at 341.63 55.88 0)
		(mirror y)
		(unit 1)
		(exclude_from_sim no)
		(in_bom yes)
		(on_board yes)
		(dnp no)
		(property "Reference" "#PWR020"
			(at 341.63 62.23 0)
			(effects
				(font
					(size 1.27 1.27)
				)
				(hide yes)
			)
		)
		(property "Value" "GND"
			(at 341.63 59.69 0)
			(effects
				(font
					(size 1.27 1.27)
				)
			)
		)
		(property "Footprint" ""
			(at 341.63 55.88 0)
			(effects
				(font
					(size 1.27 1.27)
				)
				(hide yes)
			)
		)
		(property "Datasheet" ""
			(at 341.63 55.88 0)
			(effects
				(font
					(size 1.27 1.27)
				)
				(hide yes)
			)
		)
		(property "Description" ""
			(at 341.63 55.88 0)
			(effects
				(font
					(size 1.27 1.27)
				)
				(hide yes)
			)
		)
		(property "Author" "Antmicro"
			(at 332.74 63.5 0)
			(effects
				(font
					(size 1.27 1.27)
					(thickness 0.15)
				)
				(justify left bottom)
				(hide yes)
			)
		)
		(property "License" "Apache-2.0"
			(at 332.74 66.04 0)
			(effects
				(font
					(size 1.27 1.27)
					(thickness 0.15)
				)
				(justify left bottom)
				(hide yes)
			)
		)
		(pin "1"
		)
		(instances
			(project "artix-dc-scm"
				(path ""
					(reference "#PWR020")
					(unit 1)
				)
			)
		)
	)
	(symbol
		(lib_id "antmicropower:GND")
		(at 350.52 55.88 0)
		(mirror y)
		(unit 1)
		(exclude_from_sim no)
		(in_bom yes)
		(on_board yes)
		(dnp no)
		(property "Reference" "#PWR018"
			(at 350.52 62.23 0)
			(effects
				(font
					(size 1.27 1.27)
				)
				(hide yes)
			)
		)
		(property "Value" "GND"
			(at 350.52 59.69 0)
			(effects
				(font
					(size 1.27 1.27)
				)
			)
		)
		(property "Footprint" ""
			(at 350.52 55.88 0)
			(effects
				(font
					(size 1.27 1.27)
				)
				(hide yes)
			)
		)
		(property "Datasheet" ""
			(at 350.52 55.88 0)
			(effects
				(font
					(size 1.27 1.27)
				)
				(hide yes)
			)
		)
		(property "Description" ""
			(at 350.52 55.88 0)
			(effects
				(font
					(size 1.27 1.27)
				)
				(hide yes)
			)
		)
		(property "Author" "Antmicro"
			(at 341.63 63.5 0)
			(effects
				(font
					(size 1.27 1.27)
					(thickness 0.15)
				)
				(justify left bottom)
				(hide yes)
			)
		)
		(property "License" "Apache-2.0"
			(at 341.63 66.04 0)
			(effects
				(font
					(size 1.27 1.27)
					(thickness 0.15)
				)
				(justify left bottom)
				(hide yes)
			)
		)
		(pin "1"
		)
		(instances
			(project "artix-dc-scm"
				(path ""
					(reference "#PWR018")
					(unit 1)
				)
			)
		)
	)
	(symbol
		(lib_id "antmicropower:GND")
		(at 146.05 69.85 0)
		(mirror y)
		(unit 1)
		(exclude_from_sim no)
		(in_bom yes)
		(on_board yes)
		(dnp no)
		(property "Reference" "#PWR07"
			(at 146.05 76.2 0)
			(effects
				(font
					(size 1.27 1.27)
				)
				(hide yes)
			)
		)
		(property "Value" "GND"
			(at 146.05 73.66 0)
			(effects
				(font
					(size 1.27 1.27)
				)
			)
		)
		(property "Footprint" ""
			(at 146.05 69.85 0)
			(effects
				(font
					(size 1.27 1.27)
				)
				(hide yes)
			)
		)
		(property "Datasheet" ""
			(at 146.05 69.85 0)
			(effects
				(font
					(size 1.27 1.27)
				)
				(hide yes)
			)
		)
		(property "Description" ""
			(at 146.05 69.85 0)
			(effects
				(font
					(size 1.27 1.27)
				)
				(hide yes)
			)
		)
		(property "Author" "Antmicro"
			(at 137.16 77.47 0)
			(effects
				(font
					(size 1.27 1.27)
					(thickness 0.15)
				)
				(justify left bottom)
				(hide yes)
			)
		)
		(property "License" "Apache-2.0"
			(at 137.16 80.01 0)
			(effects
				(font
					(size 1.27 1.27)
					(thickness 0.15)
				)
				(justify left bottom)
				(hide yes)
			)
		)
		(pin "1"
		)
		(instances
			(project "artix-dc-scm"
				(path ""
					(reference "#PWR07")
					(unit 1)
				)
			)
		)
	)
	(symbol
		(lib_id "antmicroResistors0402:R_1k_0402")
		(at 163.83 95.25 90)
		(mirror x)
		(unit 1)
		(exclude_from_sim no)
		(in_bom yes)
		(on_board yes)
		(dnp no)
		(property "Reference" "R1"
			(at 162.56 96.52 90)
			(effects
				(font
					(size 1.27 1.27)
				)
				(justify left)
			)
		)
		(property "Value" "R_1k_0402"
			(at 176.53 115.57 0)
			(effects
				(font
					(size 1.27 1.27)
					(thickness 0.15)
				)
				(justify left bottom)
				(hide yes)
			)
		)
		(property "Footprint" "antmicro-footprints:R_0402_1005Metric"
			(at 179.07 115.57 0)
			(effects
				(font
					(size 1.27 1.27)
					(thickness 0.15)
				)
				(justify left bottom)
				(hide yes)
			)
		)
		(property "Datasheet" "https://www.bourns.com/docs/product-datasheets/cr.pdf"
			(at 181.61 115.57 0)
			(effects
				(font
					(size 1.27 1.27)
					(thickness 0.15)
				)
				(justify left bottom)
				(hide yes)
			)
		)
		(property "Description" "SMD Chip Resistor, 1 kohm, ± 1%, 63 mW, 0402 [1005 Metric], Thick Film, General Purpose"
			(at 163.83 95.25 0)
			(effects
				(font
					(size 1.27 1.27)
				)
				(hide yes)
			)
		)
		(property "Manufacturer" "Bourns"
			(at 186.69 115.57 0)
			(effects
				(font
					(size 1.27 1.27)
					(thickness 0.15)
				)
				(justify left bottom)
				(hide yes)
			)
		)
		(property "MPN" "CR0402-FX-1001GLF"
			(at 184.15 115.57 0)
			(effects
				(font
					(size 1.27 1.27)
					(thickness 0.15)
				)
				(justify left bottom)
				(hide yes)
			)
		)
		(property "Val" "1k"
			(at 162.56 99.06 90)
			(effects
				(font
					(size 1.27 1.27)
					(thickness 0.15)
				)
				(justify left)
			)
		)
		(property "License" "Apache-2.0"
			(at 189.23 115.57 0)
			(effects
				(font
					(size 1.27 1.27)
					(thickness 0.15)
				)
				(justify left bottom)
				(hide yes)
			)
		)
		(property "Author" "Antmicro"
			(at 191.77 115.57 0)
			(effects
				(font
					(size 1.27 1.27)
					(thickness 0.15)
				)
				(justify left bottom)
				(hide yes)
			)
		)
		(property "Tolerance" "1%"
			(at 173.99 115.57 0)
			(effects
				(font
					(size 1.27 1.27)
				)
				(justify left bottom)
				(hide yes)
			)
		)
		(pin "1"
		)
		(pin "2"
		)
		(instances
			(project "artix-dc-scm"
				(path ""
					(reference "R1")
					(unit 1)
				)
			)
		)
	)
	(symbol
		(lib_id "antmicroCapacitors0402:C_470n_0402")
		(at 218.44 71.12 90)
		(unit 1)
		(exclude_from_sim no)
		(in_bom yes)
		(on_board yes)
		(dnp no)
		(property "Reference" "C123"
			(at 219.075 66.675 90)
			(effects
				(font
					(size 1.27 1.27)
				)
				(justify right)
			)
		)
		(property "Value" "C_470n_0402"
			(at 228.6 50.8 0)
			(effects
				(font
					(size 1.27 1.27)
					(thickness 0.15)
				)
				(justify left bottom)
				(hide yes)
			)
		)
		(property "Footprint" "antmicro-footprints:C_0402_1005Metric"
			(at 231.14 50.8 0)
			(effects
				(font
					(size 1.27 1.27)
					(thickness 0.15)
				)
				(justify left bottom)
				(hide yes)
			)
		)
		(property "Datasheet" "https://product.tdk.com/en/search/capacitor/ceramic/mlcc/info?part_no=C1005X5R1E474M050BB"
			(at 233.68 50.8 0)
			(effects
				(font
					(size 1.27 1.27)
					(thickness 0.15)
				)
				(justify left bottom)
				(hide yes)
			)
		)
		(property "Description" "SMD Multilayer Ceramic Capacitor, 0.47 µF, 25 V, 0402 [1005 Metric], ± 20%, X5R, C"
			(at 218.44 71.12 0)
			(effects
				(font
					(size 1.27 1.27)
				)
				(hide yes)
			)
		)
		(property "Manufacturer" "TDK"
			(at 238.76 50.8 0)
			(effects
				(font
					(size 1.27 1.27)
					(thickness 0.15)
				)
				(justify left bottom)
				(hide yes)
			)
		)
		(property "MPN" "C1005X5R1E474M050BB"
			(at 236.22 50.8 0)
			(effects
				(font
					(size 1.27 1.27)
					(thickness 0.15)
				)
				(justify left bottom)
				(hide yes)
			)
		)
		(property "Val" "470n"
			(at 219.075 70.485 90)
			(effects
				(font
					(size 1.27 1.27)
					(thickness 0.15)
				)
				(justify right)
			)
		)
		(property "License" "Apache-2.0"
			(at 241.3 50.8 0)
			(effects
				(font
					(size 1.27 1.27)
					(thickness 0.15)
				)
				(justify left bottom)
				(hide yes)
			)
		)
		(property "Author" "Antmicro"
			(at 243.84 50.8 0)
			(effects
				(font
					(size 1.27 1.27)
					(thickness 0.15)
				)
				(justify left bottom)
				(hide yes)
			)
		)
		(property "Voltage" ""
			(at 246.38 50.8 0)
			(effects
				(font
					(size 1.27 1.27)
				)
				(justify left bottom)
				(hide yes)
			)
		)
		(property "Dielectric" ""
			(at 248.92 50.8 0)
			(effects
				(font
					(size 1.27 1.27)
				)
				(justify left bottom)
				(hide yes)
			)
		)
		(pin "1"
		)
		(pin "2"
		)
		(instances
			(project "artix-dc-scm"
				(path ""
					(reference "C123")
					(unit 1)
				)
			)
		)
	)
	(symbol
		(lib_id "antmicropower:GND")
		(at 245.11 57.15 0)
		(unit 1)
		(exclude_from_sim no)
		(in_bom yes)
		(on_board yes)
		(dnp no)
		(property "Reference" "#PWR0229"
			(at 245.11 63.5 0)
			(effects
				(font
					(size 1.27 1.27)
				)
				(hide yes)
			)
		)
		(property "Value" "GND"
			(at 245.11 60.96 0)
			(effects
				(font
					(size 1.27 1.27)
				)
			)
		)
		(property "Footprint" ""
			(at 245.11 57.15 0)
			(effects
				(font
					(size 1.27 1.27)
				)
				(hide yes)
			)
		)
		(property "Datasheet" ""
			(at 245.11 57.15 0)
			(effects
				(font
					(size 1.27 1.27)
				)
				(hide yes)
			)
		)
		(property "Description" ""
			(at 245.11 57.15 0)
			(effects
				(font
					(size 1.27 1.27)
				)
				(hide yes)
			)
		)
		(property "Author" "Antmicro"
			(at 254 64.77 0)
			(effects
				(font
					(size 1.27 1.27)
					(thickness 0.15)
				)
				(justify left bottom)
				(hide yes)
			)
		)
		(property "License" "Apache-2.0"
			(at 254 67.31 0)
			(effects
				(font
					(size 1.27 1.27)
					(thickness 0.15)
				)
				(justify left bottom)
				(hide yes)
			)
		)
		(pin "1"
		)
		(instances
			(project "artix-dc-scm"
				(path ""
					(reference "#PWR0229")
					(unit 1)
				)
			)
		)
	)
	(symbol
		(lib_id "antmicropower:GND")
		(at 332.74 55.88 0)
		(mirror y)
		(unit 1)
		(exclude_from_sim no)
		(in_bom yes)
		(on_board yes)
		(dnp no)
		(property "Reference" "#PWR022"
			(at 332.74 62.23 0)
			(effects
				(font
					(size 1.27 1.27)
				)
				(hide yes)
			)
		)
		(property "Value" "GND"
			(at 332.74 59.69 0)
			(effects
				(font
					(size 1.27 1.27)
				)
			)
		)
		(property "Footprint" ""
			(at 332.74 55.88 0)
			(effects
				(font
					(size 1.27 1.27)
				)
				(hide yes)
			)
		)
		(property "Datasheet" ""
			(at 332.74 55.88 0)
			(effects
				(font
					(size 1.27 1.27)
				)
				(hide yes)
			)
		)
		(property "Description" ""
			(at 332.74 55.88 0)
			(effects
				(font
					(size 1.27 1.27)
				)
				(hide yes)
			)
		)
		(property "Author" "Antmicro"
			(at 323.85 63.5 0)
			(effects
				(font
					(size 1.27 1.27)
					(thickness 0.15)
				)
				(justify left bottom)
				(hide yes)
			)
		)
		(property "License" "Apache-2.0"
			(at 323.85 66.04 0)
			(effects
				(font
					(size 1.27 1.27)
					(thickness 0.15)
				)
				(justify left bottom)
				(hide yes)
			)
		)
		(pin "1"
		)
		(instances
			(project "artix-dc-scm"
				(path ""
					(reference "#PWR022")
					(unit 1)
				)
			)
		)
	)
	(symbol
		(lib_id "antmicropower:GND")
		(at 341.63 69.85 0)
		(mirror y)
		(unit 1)
		(exclude_from_sim no)
		(in_bom yes)
		(on_board yes)
		(dnp no)
		(property "Reference" "#PWR021"
			(at 341.63 76.2 0)
			(effects
				(font
					(size 1.27 1.27)
				)
				(hide yes)
			)
		)
		(property "Value" "GND"
			(at 341.63 73.66 0)
			(effects
				(font
					(size 1.27 1.27)
				)
			)
		)
		(property "Footprint" ""
			(at 341.63 69.85 0)
			(effects
				(font
					(size 1.27 1.27)
				)
				(hide yes)
			)
		)
		(property "Datasheet" ""
			(at 341.63 69.85 0)
			(effects
				(font
					(size 1.27 1.27)
				)
				(hide yes)
			)
		)
		(property "Description" ""
			(at 341.63 69.85 0)
			(effects
				(font
					(size 1.27 1.27)
				)
				(hide yes)
			)
		)
		(property "Author" "Antmicro"
			(at 332.74 77.47 0)
			(effects
				(font
					(size 1.27 1.27)
					(thickness 0.15)
				)
				(justify left bottom)
				(hide yes)
			)
		)
		(property "License" "Apache-2.0"
			(at 332.74 80.01 0)
			(effects
				(font
					(size 1.27 1.27)
					(thickness 0.15)
				)
				(justify left bottom)
				(hide yes)
			)
		)
		(pin "1"
		)
		(instances
			(project "artix-dc-scm"
				(path ""
					(reference "#PWR021")
					(unit 1)
				)
			)
		)
	)
	(symbol
		(lib_id "antmicropower:GND")
		(at 236.22 57.15 0)
		(unit 1)
		(exclude_from_sim no)
		(in_bom yes)
		(on_board yes)
		(dnp no)
		(property "Reference" "#PWR0228"
			(at 236.22 63.5 0)
			(effects
				(font
					(size 1.27 1.27)
				)
				(hide yes)
			)
		)
		(property "Value" "GND"
			(at 236.22 60.96 0)
			(effects
				(font
					(size 1.27 1.27)
				)
			)
		)
		(property "Footprint" ""
			(at 236.22 57.15 0)
			(effects
				(font
					(size 1.27 1.27)
				)
				(hide yes)
			)
		)
		(property "Datasheet" ""
			(at 236.22 57.15 0)
			(effects
				(font
					(size 1.27 1.27)
				)
				(hide yes)
			)
		)
		(property "Description" ""
			(at 236.22 57.15 0)
			(effects
				(font
					(size 1.27 1.27)
				)
				(hide yes)
			)
		)
		(property "Author" "Antmicro"
			(at 245.11 64.77 0)
			(effects
				(font
					(size 1.27 1.27)
					(thickness 0.15)
				)
				(justify left bottom)
				(hide yes)
			)
		)
		(property "License" "Apache-2.0"
			(at 245.11 67.31 0)
			(effects
				(font
					(size 1.27 1.27)
					(thickness 0.15)
				)
				(justify left bottom)
				(hide yes)
			)
		)
		(pin "1"
		)
		(instances
			(project "artix-dc-scm"
				(path ""
					(reference "#PWR0228")
					(unit 1)
				)
			)
		)
	)
	(symbol
		(lib_id "antmicropower:GND")
		(at 128.27 55.88 0)
		(mirror y)
		(unit 1)
		(exclude_from_sim no)
		(in_bom yes)
		(on_board yes)
		(dnp no)
		(property "Reference" "#PWR012"
			(at 128.27 62.23 0)
			(effects
				(font
					(size 1.27 1.27)
				)
				(hide yes)
			)
		)
		(property "Value" "GND"
			(at 128.27 59.69 0)
			(effects
				(font
					(size 1.27 1.27)
				)
			)
		)
		(property "Footprint" ""
			(at 128.27 55.88 0)
			(effects
				(font
					(size 1.27 1.27)
				)
				(hide yes)
			)
		)
		(property "Datasheet" ""
			(at 128.27 55.88 0)
			(effects
				(font
					(size 1.27 1.27)
				)
				(hide yes)
			)
		)
		(property "Description" ""
			(at 128.27 55.88 0)
			(effects
				(font
					(size 1.27 1.27)
				)
				(hide yes)
			)
		)
		(property "Author" "Antmicro"
			(at 119.38 63.5 0)
			(effects
				(font
					(size 1.27 1.27)
					(thickness 0.15)
				)
				(justify left bottom)
				(hide yes)
			)
		)
		(property "License" "Apache-2.0"
			(at 119.38 66.04 0)
			(effects
				(font
					(size 1.27 1.27)
					(thickness 0.15)
				)
				(justify left bottom)
				(hide yes)
			)
		)
		(pin "1"
		)
		(instances
			(project "artix-dc-scm"
				(path ""
					(reference "#PWR012")
					(unit 1)
				)
			)
		)
	)
	(symbol
		(lib_id "antmicroCapacitors0402:C_470n_0402")
		(at 41.91 57.15 90)
		(unit 1)
		(exclude_from_sim no)
		(in_bom yes)
		(on_board yes)
		(dnp no)
		(property "Reference" "C113"
			(at 42.545 52.705 90)
			(effects
				(font
					(size 1.27 1.27)
				)
				(justify right)
			)
		)
		(property "Value" "C_470n_0402"
			(at 52.07 36.83 0)
			(effects
				(font
					(size 1.27 1.27)
					(thickness 0.15)
				)
				(justify left bottom)
				(hide yes)
			)
		)
		(property "Footprint" "antmicro-footprints:C_0402_1005Metric"
			(at 54.61 36.83 0)
			(effects
				(font
					(size 1.27 1.27)
					(thickness 0.15)
				)
				(justify left bottom)
				(hide yes)
			)
		)
		(property "Datasheet" "https://product.tdk.com/en/search/capacitor/ceramic/mlcc/info?part_no=C1005X5R1E474M050BB"
			(at 57.15 36.83 0)
			(effects
				(font
					(size 1.27 1.27)
					(thickness 0.15)
				)
				(justify left bottom)
				(hide yes)
			)
		)
		(property "Description" "SMD Multilayer Ceramic Capacitor, 0.47 µF, 25 V, 0402 [1005 Metric], ± 20%, X5R, C"
			(at 41.91 57.15 0)
			(effects
				(font
					(size 1.27 1.27)
				)
				(hide yes)
			)
		)
		(property "Manufacturer" "TDK"
			(at 62.23 36.83 0)
			(effects
				(font
					(size 1.27 1.27)
					(thickness 0.15)
				)
				(justify left bottom)
				(hide yes)
			)
		)
		(property "MPN" "C1005X5R1E474M050BB"
			(at 59.69 36.83 0)
			(effects
				(font
					(size 1.27 1.27)
					(thickness 0.15)
				)
				(justify left bottom)
				(hide yes)
			)
		)
		(property "Val" "470n"
			(at 42.545 56.515 90)
			(effects
				(font
					(size 1.27 1.27)
					(thickness 0.15)
				)
				(justify right)
			)
		)
		(property "License" "Apache-2.0"
			(at 64.77 36.83 0)
			(effects
				(font
					(size 1.27 1.27)
					(thickness 0.15)
				)
				(justify left bottom)
				(hide yes)
			)
		)
		(property "Author" "Antmicro"
			(at 67.31 36.83 0)
			(effects
				(font
					(size 1.27 1.27)
					(thickness 0.15)
				)
				(justify left bottom)
				(hide yes)
			)
		)
		(property "Voltage" ""
			(at 69.85 36.83 0)
			(effects
				(font
					(size 1.27 1.27)
				)
				(justify left bottom)
				(hide yes)
			)
		)
		(property "Dielectric" ""
			(at 72.39 36.83 0)
			(effects
				(font
					(size 1.27 1.27)
				)
				(justify left bottom)
				(hide yes)
			)
		)
		(pin "1"
		)
		(pin "2"
		)
		(instances
			(project "artix-dc-scm"
				(path ""
					(reference "C113")
					(unit 1)
				)
			)
		)
	)
	(symbol
		(lib_id "antmicropower:GND")
		(at 41.91 71.12 0)
		(unit 1)
		(exclude_from_sim no)
		(in_bom yes)
		(on_board yes)
		(dnp no)
		(property "Reference" "#PWR0217"
			(at 41.91 77.47 0)
			(effects
				(font
					(size 1.27 1.27)
				)
				(hide yes)
			)
		)
		(property "Value" "GND"
			(at 41.91 74.93 0)
			(effects
				(font
					(size 1.27 1.27)
				)
			)
		)
		(property "Footprint" ""
			(at 41.91 71.12 0)
			(effects
				(font
					(size 1.27 1.27)
				)
				(hide yes)
			)
		)
		(property "Datasheet" ""
			(at 41.91 71.12 0)
			(effects
				(font
					(size 1.27 1.27)
				)
				(hide yes)
			)
		)
		(property "Description" ""
			(at 41.91 71.12 0)
			(effects
				(font
					(size 1.27 1.27)
				)
				(hide yes)
			)
		)
		(property "Author" "Antmicro"
			(at 50.8 78.74 0)
			(effects
				(font
					(size 1.27 1.27)
					(thickness 0.15)
				)
				(justify left bottom)
				(hide yes)
			)
		)
		(property "License" "Apache-2.0"
			(at 50.8 81.28 0)
			(effects
				(font
					(size 1.27 1.27)
					(thickness 0.15)
				)
				(justify left bottom)
				(hide yes)
			)
		)
		(pin "1"
		)
		(instances
			(project "artix-dc-scm"
				(path ""
					(reference "#PWR0217")
					(unit 1)
				)
			)
		)
	)
	(symbol
		(lib_id "antmicropower:GND")
		(at 365.76 158.75 0)
		(mirror y)
		(unit 1)
		(exclude_from_sim no)
		(in_bom yes)
		(on_board yes)
		(dnp no)
		(property "Reference" "#PWR014"
			(at 365.76 165.1 0)
			(effects
				(font
					(size 1.27 1.27)
				)
				(hide yes)
			)
		)
		(property "Value" "GND"
			(at 365.76 162.56 0)
			(effects
				(font
					(size 1.27 1.27)
				)
			)
		)
		(property "Footprint" ""
			(at 365.76 158.75 0)
			(effects
				(font
					(size 1.27 1.27)
				)
				(hide yes)
			)
		)
		(property "Datasheet" ""
			(at 365.76 158.75 0)
			(effects
				(font
					(size 1.27 1.27)
				)
				(hide yes)
			)
		)
		(property "Description" ""
			(at 365.76 158.75 0)
			(effects
				(font
					(size 1.27 1.27)
				)
				(hide yes)
			)
		)
		(property "Author" "Antmicro"
			(at 356.87 166.37 0)
			(effects
				(font
					(size 1.27 1.27)
					(thickness 0.15)
				)
				(justify left bottom)
				(hide yes)
			)
		)
		(property "License" "Apache-2.0"
			(at 356.87 168.91 0)
			(effects
				(font
					(size 1.27 1.27)
					(thickness 0.15)
				)
				(justify left bottom)
				(hide yes)
			)
		)
		(pin "1"
		)
		(instances
			(project "artix-dc-scm"
				(path ""
					(reference "#PWR014")
					(unit 1)
				)
			)
		)
	)
	(symbol
		(lib_id "antmicropower:GND")
		(at 236.22 71.12 0)
		(unit 1)
		(exclude_from_sim no)
		(in_bom yes)
		(on_board yes)
		(dnp no)
		(property "Reference" "#PWR0231"
			(at 236.22 77.47 0)
			(effects
				(font
					(size 1.27 1.27)
				)
				(hide yes)
			)
		)
		(property "Value" "GND"
			(at 236.22 74.93 0)
			(effects
				(font
					(size 1.27 1.27)
				)
			)
		)
		(property "Footprint" ""
			(at 236.22 71.12 0)
			(effects
				(font
					(size 1.27 1.27)
				)
				(hide yes)
			)
		)
		(property "Datasheet" ""
			(at 236.22 71.12 0)
			(effects
				(font
					(size 1.27 1.27)
				)
				(hide yes)
			)
		)
		(property "Description" ""
			(at 236.22 71.12 0)
			(effects
				(font
					(size 1.27 1.27)
				)
				(hide yes)
			)
		)
		(property "Author" "Antmicro"
			(at 245.11 78.74 0)
			(effects
				(font
					(size 1.27 1.27)
					(thickness 0.15)
				)
				(justify left bottom)
				(hide yes)
			)
		)
		(property "License" "Apache-2.0"
			(at 245.11 81.28 0)
			(effects
				(font
					(size 1.27 1.27)
					(thickness 0.15)
				)
				(justify left bottom)
				(hide yes)
			)
		)
		(pin "1"
		)
		(instances
			(project "artix-dc-scm"
				(path ""
					(reference "#PWR0231")
					(unit 1)
				)
			)
		)
	)
	(symbol
		(lib_id "antmicroCapacitorsmisc:C_47u_1210")
		(at 359.41 55.88 270)
		(mirror x)
		(unit 1)
		(exclude_from_sim no)
		(in_bom yes)
		(on_board yes)
		(dnp no)
		(property "Reference" "C92"
			(at 358.775 51.435 90)
			(effects
				(font
					(size 1.27 1.27)
				)
				(justify right)
			)
		)
		(property "Value" "C_47u_1210"
			(at 349.25 35.56 0)
			(effects
				(font
					(size 1.27 1.27)
					(thickness 0.15)
				)
				(justify left bottom)
				(hide yes)
			)
		)
		(property "Footprint" "antmicro-footprints:C_1210_3225Metric"
			(at 346.71 35.56 0)
			(effects
				(font
					(size 1.27 1.27)
					(thickness 0.15)
				)
				(justify left bottom)
				(hide yes)
			)
		)
		(property "Datasheet" "https://www.kemet.com/en/us/capacitors/product/C1210C476K8RACTU.html"
			(at 344.17 35.56 0)
			(effects
				(font
					(size 1.27 1.27)
					(thickness 0.15)
				)
				(justify left bottom)
				(hide yes)
			)
		)
		(property "Description" "SMD Multilayer Ceramic Capacitor, 47 µF, 10 V, 1210 [3225 Metric], ± 10%, X7R, C Series KEMET"
			(at 359.41 55.88 0)
			(effects
				(font
					(size 1.27 1.27)
				)
				(hide yes)
			)
		)
		(property "Manufacturer" "KEMET"
			(at 339.09 35.56 0)
			(effects
				(font
					(size 1.27 1.27)
					(thickness 0.15)
				)
				(justify left bottom)
				(hide yes)
			)
		)
		(property "MPN" "C1210C476K8RACTU"
			(at 341.63 35.56 0)
			(effects
				(font
					(size 1.27 1.27)
					(thickness 0.15)
				)
				(justify left bottom)
				(hide yes)
			)
		)
		(property "Val" "47u"
			(at 358.775 55.245 90)
			(effects
				(font
					(size 1.27 1.27)
					(thickness 0.15)
				)
				(justify right)
			)
		)
		(property "License" "Apache-2.0"
			(at 336.55 35.56 0)
			(effects
				(font
					(size 1.27 1.27)
					(thickness 0.15)
				)
				(justify left bottom)
				(hide yes)
			)
		)
		(property "Author" "Antmicro"
			(at 334.01 35.56 0)
			(effects
				(font
					(size 1.27 1.27)
					(thickness 0.15)
				)
				(justify left bottom)
				(hide yes)
			)
		)
		(property "Voltage" ""
			(at 331.47 35.56 0)
			(effects
				(font
					(size 1.27 1.27)
				)
				(justify left bottom)
				(hide yes)
			)
		)
		(property "Dielectric" ""
			(at 328.93 35.56 0)
			(effects
				(font
					(size 1.27 1.27)
				)
				(justify left bottom)
				(hide yes)
			)
		)
		(property "Public" "False"
			(at 326.39 35.56 0)
			(effects
				(font
					(size 1.27 1.27)
				)
				(justify left bottom)
				(hide yes)
			)
		)
		(property "DNP" ""
			(at 359.41 55.88 0)
			(effects
				(font
					(size 1.27 1.27)
				)
			)
		)
		(pin "1"
		)
		(pin "2"
		)
		(instances
			(project "artix-dc-scm"
				(path ""
					(reference "C92")
					(unit 1)
				)
			)
		)
	)
	(symbol
		(lib_id "antmicropower:GND")
		(at 137.16 55.88 0)
		(mirror y)
		(unit 1)
		(exclude_from_sim no)
		(in_bom yes)
		(on_board yes)
		(dnp no)
		(property "Reference" "#PWR010"
			(at 137.16 62.23 0)
			(effects
				(font
					(size 1.27 1.27)
				)
				(hide yes)
			)
		)
		(property "Value" "GND"
			(at 137.16 59.69 0)
			(effects
				(font
					(size 1.27 1.27)
				)
			)
		)
		(property "Footprint" ""
			(at 137.16 55.88 0)
			(effects
				(font
					(size 1.27 1.27)
				)
				(hide yes)
			)
		)
		(property "Datasheet" ""
			(at 137.16 55.88 0)
			(effects
				(font
					(size 1.27 1.27)
				)
				(hide yes)
			)
		)
		(property "Description" ""
			(at 137.16 55.88 0)
			(effects
				(font
					(size 1.27 1.27)
				)
				(hide yes)
			)
		)
		(property "Author" "Antmicro"
			(at 128.27 63.5 0)
			(effects
				(font
					(size 1.27 1.27)
					(thickness 0.15)
				)
				(justify left bottom)
				(hide yes)
			)
		)
		(property "License" "Apache-2.0"
			(at 128.27 66.04 0)
			(effects
				(font
					(size 1.27 1.27)
					(thickness 0.15)
				)
				(justify left bottom)
				(hide yes)
			)
		)
		(pin "1"
		)
		(instances
			(project "artix-dc-scm"
				(path ""
					(reference "#PWR010")
					(unit 1)
				)
			)
		)
	)
	(symbol
		(lib_id "antmicroCapacitors0402:C_470n_0402")
		(at 137.16 69.85 270)
		(mirror x)
		(unit 1)
		(exclude_from_sim no)
		(in_bom yes)
		(on_board yes)
		(dnp no)
		(property "Reference" "C130"
			(at 136.525 65.405 90)
			(effects
				(font
					(size 1.27 1.27)
				)
				(justify right)
			)
		)
		(property "Value" "C_470n_0402"
			(at 127 49.53 0)
			(effects
				(font
					(size 1.27 1.27)
					(thickness 0.15)
				)
				(justify left bottom)
				(hide yes)
			)
		)
		(property "Footprint" "antmicro-footprints:C_0402_1005Metric"
			(at 124.46 49.53 0)
			(effects
				(font
					(size 1.27 1.27)
					(thickness 0.15)
				)
				(justify left bottom)
				(hide yes)
			)
		)
		(property "Datasheet" "https://product.tdk.com/en/search/capacitor/ceramic/mlcc/info?part_no=C1005X5R1E474M050BB"
			(at 121.92 49.53 0)
			(effects
				(font
					(size 1.27 1.27)
					(thickness 0.15)
				)
				(justify left bottom)
				(hide yes)
			)
		)
		(property "Description" "SMD Multilayer Ceramic Capacitor, 0.47 µF, 25 V, 0402 [1005 Metric], ± 20%, X5R, C"
			(at 137.16 69.85 0)
			(effects
				(font
					(size 1.27 1.27)
				)
				(hide yes)
			)
		)
		(property "Manufacturer" "TDK"
			(at 116.84 49.53 0)
			(effects
				(font
					(size 1.27 1.27)
					(thickness 0.15)
				)
				(justify left bottom)
				(hide yes)
			)
		)
		(property "MPN" "C1005X5R1E474M050BB"
			(at 119.38 49.53 0)
			(effects
				(font
					(size 1.27 1.27)
					(thickness 0.15)
				)
				(justify left bottom)
				(hide yes)
			)
		)
		(property "Val" "470n"
			(at 136.525 69.215 90)
			(effects
				(font
					(size 1.27 1.27)
					(thickness 0.15)
				)
				(justify right)
			)
		)
		(property "License" "Apache-2.0"
			(at 114.3 49.53 0)
			(effects
				(font
					(size 1.27 1.27)
					(thickness 0.15)
				)
				(justify left bottom)
				(hide yes)
			)
		)
		(property "Author" "Antmicro"
			(at 111.76 49.53 0)
			(effects
				(font
					(size 1.27 1.27)
					(thickness 0.15)
				)
				(justify left bottom)
				(hide yes)
			)
		)
		(property "Voltage" ""
			(at 109.22 49.53 0)
			(effects
				(font
					(size 1.27 1.27)
				)
				(justify left bottom)
				(hide yes)
			)
		)
		(property "Dielectric" ""
			(at 106.68 49.53 0)
			(effects
				(font
					(size 1.27 1.27)
				)
				(justify left bottom)
				(hide yes)
			)
		)
		(property "DNP" ""
			(at 137.16 69.85 0)
			(effects
				(font
					(size 1.27 1.27)
				)
			)
		)
		(pin "1"
		)
		(pin "2"
		)
		(instances
			(project "artix-dc-scm"
				(path ""
					(reference "C130")
					(unit 1)
				)
			)
		)
	)
	(symbol
		(lib_id "antmicropower:GND")
		(at 146.05 55.88 0)
		(mirror y)
		(unit 1)
		(exclude_from_sim no)
		(in_bom yes)
		(on_board yes)
		(dnp no)
		(property "Reference" "#PWR05"
			(at 146.05 62.23 0)
			(effects
				(font
					(size 1.27 1.27)
				)
				(hide yes)
			)
		)
		(property "Value" "GND"
			(at 146.05 59.69 0)
			(effects
				(font
					(size 1.27 1.27)
				)
			)
		)
		(property "Footprint" ""
			(at 146.05 55.88 0)
			(effects
				(font
					(size 1.27 1.27)
				)
				(hide yes)
			)
		)
		(property "Datasheet" ""
			(at 146.05 55.88 0)
			(effects
				(font
					(size 1.27 1.27)
				)
				(hide yes)
			)
		)
		(property "Description" ""
			(at 146.05 55.88 0)
			(effects
				(font
					(size 1.27 1.27)
				)
				(hide yes)
			)
		)
		(property "Author" "Antmicro"
			(at 137.16 63.5 0)
			(effects
				(font
					(size 1.27 1.27)
					(thickness 0.15)
				)
				(justify left bottom)
				(hide yes)
			)
		)
		(property "License" "Apache-2.0"
			(at 137.16 66.04 0)
			(effects
				(font
					(size 1.27 1.27)
					(thickness 0.15)
				)
				(justify left bottom)
				(hide yes)
			)
		)
		(pin "1"
		)
		(instances
			(project "artix-dc-scm"
				(path ""
					(reference "#PWR05")
					(unit 1)
				)
			)
		)
	)
	(symbol
		(lib_id "antmicropower:GND")
		(at 227.33 71.12 0)
		(unit 1)
		(exclude_from_sim no)
		(in_bom yes)
		(on_board yes)
		(dnp no)
		(property "Reference" "#PWR0232"
			(at 227.33 77.47 0)
			(effects
				(font
					(size 1.27 1.27)
				)
				(hide yes)
			)
		)
		(property "Value" "GND"
			(at 227.33 74.93 0)
			(effects
				(font
					(size 1.27 1.27)
				)
			)
		)
		(property "Footprint" ""
			(at 227.33 71.12 0)
			(effects
				(font
					(size 1.27 1.27)
				)
				(hide yes)
			)
		)
		(property "Datasheet" ""
			(at 227.33 71.12 0)
			(effects
				(font
					(size 1.27 1.27)
				)
				(hide yes)
			)
		)
		(property "Description" ""
			(at 227.33 71.12 0)
			(effects
				(font
					(size 1.27 1.27)
				)
				(hide yes)
			)
		)
		(property "Author" "Antmicro"
			(at 236.22 78.74 0)
			(effects
				(font
					(size 1.27 1.27)
					(thickness 0.15)
				)
				(justify left bottom)
				(hide yes)
			)
		)
		(property "License" "Apache-2.0"
			(at 236.22 81.28 0)
			(effects
				(font
					(size 1.27 1.27)
					(thickness 0.15)
				)
				(justify left bottom)
				(hide yes)
			)
		)
		(pin "1"
		)
		(instances
			(project "artix-dc-scm"
				(path ""
					(reference "#PWR0232")
					(unit 1)
				)
			)
		)
	)
	(symbol
		(lib_id "antmicroCapacitors0402:C_470n_0402")
		(at 128.27 55.88 270)
		(mirror x)
		(unit 1)
		(exclude_from_sim no)
		(in_bom yes)
		(on_board yes)
		(dnp no)
		(property "Reference" "C112"
			(at 127.635 51.435 90)
			(effects
				(font
					(size 1.27 1.27)
				)
				(justify right)
			)
		)
		(property "Value" "C_470n_0402"
			(at 118.11 35.56 0)
			(effects
				(font
					(size 1.27 1.27)
					(thickness 0.15)
				)
				(justify left bottom)
				(hide yes)
			)
		)
		(property "Footprint" "antmicro-footprints:C_0402_1005Metric"
			(at 115.57 35.56 0)
			(effects
				(font
					(size 1.27 1.27)
					(thickness 0.15)
				)
				(justify left bottom)
				(hide yes)
			)
		)
		(property "Datasheet" "https://product.tdk.com/en/search/capacitor/ceramic/mlcc/info?part_no=C1005X5R1E474M050BB"
			(at 113.03 35.56 0)
			(effects
				(font
					(size 1.27 1.27)
					(thickness 0.15)
				)
				(justify left bottom)
				(hide yes)
			)
		)
		(property "Description" "SMD Multilayer Ceramic Capacitor, 0.47 µF, 25 V, 0402 [1005 Metric], ± 20%, X5R, C"
			(at 128.27 55.88 0)
			(effects
				(font
					(size 1.27 1.27)
				)
				(hide yes)
			)
		)
		(property "Manufacturer" "TDK"
			(at 107.95 35.56 0)
			(effects
				(font
					(size 1.27 1.27)
					(thickness 0.15)
				)
				(justify left bottom)
				(hide yes)
			)
		)
		(property "MPN" "C1005X5R1E474M050BB"
			(at 110.49 35.56 0)
			(effects
				(font
					(size 1.27 1.27)
					(thickness 0.15)
				)
				(justify left bottom)
				(hide yes)
			)
		)
		(property "Val" "470n"
			(at 127.635 55.245 90)
			(effects
				(font
					(size 1.27 1.27)
					(thickness 0.15)
				)
				(justify right)
			)
		)
		(property "License" "Apache-2.0"
			(at 105.41 35.56 0)
			(effects
				(font
					(size 1.27 1.27)
					(thickness 0.15)
				)
				(justify left bottom)
				(hide yes)
			)
		)
		(property "Author" "Antmicro"
			(at 102.87 35.56 0)
			(effects
				(font
					(size 1.27 1.27)
					(thickness 0.15)
				)
				(justify left bottom)
				(hide yes)
			)
		)
		(property "Voltage" ""
			(at 100.33 35.56 0)
			(effects
				(font
					(size 1.27 1.27)
				)
				(justify left bottom)
				(hide yes)
			)
		)
		(property "Dielectric" ""
			(at 97.79 35.56 0)
			(effects
				(font
					(size 1.27 1.27)
				)
				(justify left bottom)
				(hide yes)
			)
		)
		(property "DNP" ""
			(at 128.27 55.88 0)
			(effects
				(font
					(size 1.27 1.27)
				)
			)
		)
		(pin "1"
		)
		(pin "2"
		)
		(instances
			(project "artix-dc-scm"
				(path ""
					(reference "C112")
					(unit 1)
				)
			)
		)
	)
	(symbol
		(lib_id "antmicroCapacitors0402:C_470n_0402")
		(at 146.05 69.85 270)
		(mirror x)
		(unit 1)
		(exclude_from_sim no)
		(in_bom yes)
		(on_board yes)
		(dnp no)
		(property "Reference" "C124"
			(at 145.415 65.405 90)
			(effects
				(font
					(size 1.27 1.27)
				)
				(justify right)
			)
		)
		(property "Value" "C_470n_0402"
			(at 135.89 49.53 0)
			(effects
				(font
					(size 1.27 1.27)
					(thickness 0.15)
				)
				(justify left bottom)
				(hide yes)
			)
		)
		(property "Footprint" "antmicro-footprints:C_0402_1005Metric"
			(at 133.35 49.53 0)
			(effects
				(font
					(size 1.27 1.27)
					(thickness 0.15)
				)
				(justify left bottom)
				(hide yes)
			)
		)
		(property "Datasheet" "https://product.tdk.com/en/search/capacitor/ceramic/mlcc/info?part_no=C1005X5R1E474M050BB"
			(at 130.81 49.53 0)
			(effects
				(font
					(size 1.27 1.27)
					(thickness 0.15)
				)
				(justify left bottom)
				(hide yes)
			)
		)
		(property "Description" "SMD Multilayer Ceramic Capacitor, 0.47 µF, 25 V, 0402 [1005 Metric], ± 20%, X5R, C"
			(at 146.05 69.85 0)
			(effects
				(font
					(size 1.27 1.27)
				)
				(hide yes)
			)
		)
		(property "Manufacturer" "TDK"
			(at 125.73 49.53 0)
			(effects
				(font
					(size 1.27 1.27)
					(thickness 0.15)
				)
				(justify left bottom)
				(hide yes)
			)
		)
		(property "MPN" "C1005X5R1E474M050BB"
			(at 128.27 49.53 0)
			(effects
				(font
					(size 1.27 1.27)
					(thickness 0.15)
				)
				(justify left bottom)
				(hide yes)
			)
		)
		(property "Val" "470n"
			(at 145.415 69.215 90)
			(effects
				(font
					(size 1.27 1.27)
					(thickness 0.15)
				)
				(justify right)
			)
		)
		(property "License" "Apache-2.0"
			(at 123.19 49.53 0)
			(effects
				(font
					(size 1.27 1.27)
					(thickness 0.15)
				)
				(justify left bottom)
				(hide yes)
			)
		)
		(property "Author" "Antmicro"
			(at 120.65 49.53 0)
			(effects
				(font
					(size 1.27 1.27)
					(thickness 0.15)
				)
				(justify left bottom)
				(hide yes)
			)
		)
		(property "Voltage" ""
			(at 118.11 49.53 0)
			(effects
				(font
					(size 1.27 1.27)
				)
				(justify left bottom)
				(hide yes)
			)
		)
		(property "Dielectric" ""
			(at 115.57 49.53 0)
			(effects
				(font
					(size 1.27 1.27)
				)
				(justify left bottom)
				(hide yes)
			)
		)
		(property "DNP" ""
			(at 146.05 69.85 0)
			(effects
				(font
					(size 1.27 1.27)
				)
			)
		)
		(pin "1"
		)
		(pin "2"
		)
		(instances
			(project "artix-dc-scm"
				(path ""
					(reference "C124")
					(unit 1)
				)
			)
		)
	)
	(symbol
		(lib_id "antmicropower:GND")
		(at 245.11 71.12 0)
		(unit 1)
		(exclude_from_sim no)
		(in_bom yes)
		(on_board yes)
		(dnp no)
		(property "Reference" "#PWR0230"
			(at 245.11 77.47 0)
			(effects
				(font
					(size 1.27 1.27)
				)
				(hide yes)
			)
		)
		(property "Value" "GND"
			(at 245.11 74.93 0)
			(effects
				(font
					(size 1.27 1.27)
				)
			)
		)
		(property "Footprint" ""
			(at 245.11 71.12 0)
			(effects
				(font
					(size 1.27 1.27)
				)
				(hide yes)
			)
		)
		(property "Datasheet" ""
			(at 245.11 71.12 0)
			(effects
				(font
					(size 1.27 1.27)
				)
				(hide yes)
			)
		)
		(property "Description" ""
			(at 245.11 71.12 0)
			(effects
				(font
					(size 1.27 1.27)
				)
				(hide yes)
			)
		)
		(property "Author" "Antmicro"
			(at 254 78.74 0)
			(effects
				(font
					(size 1.27 1.27)
					(thickness 0.15)
				)
				(justify left bottom)
				(hide yes)
			)
		)
		(property "License" "Apache-2.0"
			(at 254 81.28 0)
			(effects
				(font
					(size 1.27 1.27)
					(thickness 0.15)
				)
				(justify left bottom)
				(hide yes)
			)
		)
		(pin "1"
		)
		(instances
			(project "artix-dc-scm"
				(path ""
					(reference "#PWR0230")
					(unit 1)
				)
			)
		)
	)
	(symbol
		(lib_id "antmicroCapacitors0402:C_470n_0402")
		(at 245.11 71.12 90)
		(unit 1)
		(exclude_from_sim no)
		(in_bom yes)
		(on_board yes)
		(dnp no)
		(property "Reference" "C240"
			(at 245.745 66.675 90)
			(effects
				(font
					(size 1.27 1.27)
				)
				(justify right)
			)
		)
		(property "Value" "C_470n_0402"
			(at 255.27 50.8 0)
			(effects
				(font
					(size 1.27 1.27)
					(thickness 0.15)
				)
				(justify left bottom)
				(hide yes)
			)
		)
		(property "Footprint" "antmicro-footprints:C_0402_1005Metric"
			(at 257.81 50.8 0)
			(effects
				(font
					(size 1.27 1.27)
					(thickness 0.15)
				)
				(justify left bottom)
				(hide yes)
			)
		)
		(property "Datasheet" "https://product.tdk.com/en/search/capacitor/ceramic/mlcc/info?part_no=C1005X5R1E474M050BB"
			(at 260.35 50.8 0)
			(effects
				(font
					(size 1.27 1.27)
					(thickness 0.15)
				)
				(justify left bottom)
				(hide yes)
			)
		)
		(property "Description" "SMD Multilayer Ceramic Capacitor, 0.47 µF, 25 V, 0402 [1005 Metric], ± 20%, X5R, C"
			(at 245.11 71.12 0)
			(effects
				(font
					(size 1.27 1.27)
				)
				(hide yes)
			)
		)
		(property "Manufacturer" "TDK"
			(at 265.43 50.8 0)
			(effects
				(font
					(size 1.27 1.27)
					(thickness 0.15)
				)
				(justify left bottom)
				(hide yes)
			)
		)
		(property "MPN" "C1005X5R1E474M050BB"
			(at 262.89 50.8 0)
			(effects
				(font
					(size 1.27 1.27)
					(thickness 0.15)
				)
				(justify left bottom)
				(hide yes)
			)
		)
		(property "Val" "470n"
			(at 245.745 70.485 90)
			(effects
				(font
					(size 1.27 1.27)
					(thickness 0.15)
				)
				(justify right)
			)
		)
		(property "License" "Apache-2.0"
			(at 267.97 50.8 0)
			(effects
				(font
					(size 1.27 1.27)
					(thickness 0.15)
				)
				(justify left bottom)
				(hide yes)
			)
		)
		(property "Author" "Antmicro"
			(at 270.51 50.8 0)
			(effects
				(font
					(size 1.27 1.27)
					(thickness 0.15)
				)
				(justify left bottom)
				(hide yes)
			)
		)
		(property "Voltage" ""
			(at 273.05 50.8 0)
			(effects
				(font
					(size 1.27 1.27)
				)
				(justify left bottom)
				(hide yes)
			)
		)
		(property "Dielectric" ""
			(at 275.59 50.8 0)
			(effects
				(font
					(size 1.27 1.27)
				)
				(justify left bottom)
				(hide yes)
			)
		)
		(pin "1"
		)
		(pin "2"
		)
		(instances
			(project "artix-dc-scm"
				(path ""
					(reference "C240")
					(unit 1)
				)
			)
		)
	)
	(symbol
		(lib_id "antmicroCapacitors0402:C_470n_0402")
		(at 323.85 55.88 270)
		(mirror x)
		(unit 1)
		(exclude_from_sim no)
		(in_bom yes)
		(on_board yes)
		(dnp no)
		(property "Reference" "C116"
			(at 323.215 51.435 90)
			(effects
				(font
					(size 1.27 1.27)
				)
				(justify right)
			)
		)
		(property "Value" "C_470n_0402"
			(at 313.69 35.56 0)
			(effects
				(font
					(size 1.27 1.27)
					(thickness 0.15)
				)
				(justify left bottom)
				(hide yes)
			)
		)
		(property "Footprint" "antmicro-footprints:C_0402_1005Metric"
			(at 311.15 35.56 0)
			(effects
				(font
					(size 1.27 1.27)
					(thickness 0.15)
				)
				(justify left bottom)
				(hide yes)
			)
		)
		(property "Datasheet" "https://product.tdk.com/en/search/capacitor/ceramic/mlcc/info?part_no=C1005X5R1E474M050BB"
			(at 308.61 35.56 0)
			(effects
				(font
					(size 1.27 1.27)
					(thickness 0.15)
				)
				(justify left bottom)
				(hide yes)
			)
		)
		(property "Description" "SMD Multilayer Ceramic Capacitor, 0.47 µF, 25 V, 0402 [1005 Metric], ± 20%, X5R, C"
			(at 323.85 55.88 0)
			(effects
				(font
					(size 1.27 1.27)
				)
				(hide yes)
			)
		)
		(property "Manufacturer" "TDK"
			(at 303.53 35.56 0)
			(effects
				(font
					(size 1.27 1.27)
					(thickness 0.15)
				)
				(justify left bottom)
				(hide yes)
			)
		)
		(property "MPN" "C1005X5R1E474M050BB"
			(at 306.07 35.56 0)
			(effects
				(font
					(size 1.27 1.27)
					(thickness 0.15)
				)
				(justify left bottom)
				(hide yes)
			)
		)
		(property "Val" "470n"
			(at 323.215 55.245 90)
			(effects
				(font
					(size 1.27 1.27)
					(thickness 0.15)
				)
				(justify right)
			)
		)
		(property "License" "Apache-2.0"
			(at 300.99 35.56 0)
			(effects
				(font
					(size 1.27 1.27)
					(thickness 0.15)
				)
				(justify left bottom)
				(hide yes)
			)
		)
		(property "Author" "Antmicro"
			(at 298.45 35.56 0)
			(effects
				(font
					(size 1.27 1.27)
					(thickness 0.15)
				)
				(justify left bottom)
				(hide yes)
			)
		)
		(property "Voltage" ""
			(at 295.91 35.56 0)
			(effects
				(font
					(size 1.27 1.27)
				)
				(justify left bottom)
				(hide yes)
			)
		)
		(property "Dielectric" ""
			(at 293.37 35.56 0)
			(effects
				(font
					(size 1.27 1.27)
				)
				(justify left bottom)
				(hide yes)
			)
		)
		(property "DNP" ""
			(at 323.85 55.88 0)
			(effects
				(font
					(size 1.27 1.27)
				)
			)
		)
		(pin "1"
		)
		(pin "2"
		)
		(instances
			(project "artix-dc-scm"
				(path ""
					(reference "C116")
					(unit 1)
				)
			)
		)
	)
	(symbol
		(lib_id "antmicropower:GND")
		(at 163.83 109.22 0)
		(mirror y)
		(unit 1)
		(exclude_from_sim no)
		(in_bom yes)
		(on_board yes)
		(dnp no)
		(property "Reference" "#PWR01"
			(at 163.83 115.57 0)
			(effects
				(font
					(size 1.27 1.27)
				)
				(hide yes)
			)
		)
		(property "Value" "GND"
			(at 163.83 113.03 0)
			(effects
				(font
					(size 1.27 1.27)
				)
			)
		)
		(property "Footprint" ""
			(at 163.83 109.22 0)
			(effects
				(font
					(size 1.27 1.27)
				)
				(hide yes)
			)
		)
		(property "Datasheet" ""
			(at 163.83 109.22 0)
			(effects
				(font
					(size 1.27 1.27)
				)
				(hide yes)
			)
		)
		(property "Description" ""
			(at 163.83 109.22 0)
			(effects
				(font
					(size 1.27 1.27)
				)
				(hide yes)
			)
		)
		(property "Author" "Antmicro"
			(at 154.94 116.84 0)
			(effects
				(font
					(size 1.27 1.27)
					(thickness 0.15)
				)
				(justify left bottom)
				(hide yes)
			)
		)
		(property "License" "Apache-2.0"
			(at 154.94 119.38 0)
			(effects
				(font
					(size 1.27 1.27)
					(thickness 0.15)
				)
				(justify left bottom)
				(hide yes)
			)
		)
		(pin "1"
		)
		(instances
			(project "artix-dc-scm"
				(path ""
					(reference "#PWR01")
					(unit 1)
				)
			)
		)
	)
	(symbol
		(lib_id "antmicroCapacitors0603:C_4u7_0603")
		(at 350.52 55.88 270)
		(mirror x)
		(unit 1)
		(exclude_from_sim no)
		(in_bom yes)
		(on_board yes)
		(dnp no)
		(property "Reference" "C98"
			(at 349.885 51.435 90)
			(effects
				(font
					(size 1.27 1.27)
				)
				(justify right)
			)
		)
		(property "Value" "C_4u7_0603"
			(at 340.36 35.56 0)
			(effects
				(font
					(size 1.27 1.27)
					(thickness 0.15)
				)
				(justify left bottom)
				(hide yes)
			)
		)
		(property "Footprint" "antmicro-footprints:C_0603_1608Metric"
			(at 337.82 35.56 0)
			(effects
				(font
					(size 1.27 1.27)
					(thickness 0.15)
				)
				(justify left bottom)
				(hide yes)
			)
		)
		(property "Datasheet" "https://product.tdk.com/en/search/capacitor/ceramic/mlcc/info?part_no=C1608X5R1V475M080AC"
			(at 335.28 35.56 0)
			(effects
				(font
					(size 1.27 1.27)
					(thickness 0.15)
				)
				(justify left bottom)
				(hide yes)
			)
		)
		(property "Description" "SMD Multilayer Ceramic Capacitor, 4.7 µF, 35 V, 0603 [1608 Metric], ± 20%, X5R, C"
			(at 350.52 55.88 0)
			(effects
				(font
					(size 1.27 1.27)
				)
				(hide yes)
			)
		)
		(property "Manufacturer" "TDK"
			(at 330.2 35.56 0)
			(effects
				(font
					(size 1.27 1.27)
					(thickness 0.15)
				)
				(justify left bottom)
				(hide yes)
			)
		)
		(property "MPN" "C1608X5R1V475M080AC"
			(at 332.74 35.56 0)
			(effects
				(font
					(size 1.27 1.27)
					(thickness 0.15)
				)
				(justify left bottom)
				(hide yes)
			)
		)
		(property "Val" "4u7"
			(at 349.885 55.245 90)
			(effects
				(font
					(size 1.27 1.27)
					(thickness 0.15)
				)
				(justify right)
			)
		)
		(property "License" "Apache-2.0"
			(at 327.66 35.56 0)
			(effects
				(font
					(size 1.27 1.27)
					(thickness 0.15)
				)
				(justify left bottom)
				(hide yes)
			)
		)
		(property "Author" "Antmicro"
			(at 325.12 35.56 0)
			(effects
				(font
					(size 1.27 1.27)
					(thickness 0.15)
				)
				(justify left bottom)
				(hide yes)
			)
		)
		(property "Voltage" ""
			(at 322.58 35.56 0)
			(effects
				(font
					(size 1.27 1.27)
				)
				(justify left bottom)
				(hide yes)
			)
		)
		(property "Dielectric" ""
			(at 320.04 35.56 0)
			(effects
				(font
					(size 1.27 1.27)
				)
				(justify left bottom)
				(hide yes)
			)
		)
		(property "DNP" ""
			(at 350.52 55.88 0)
			(effects
				(font
					(size 1.27 1.27)
				)
			)
		)
		(pin "1"
		)
		(pin "2"
		)
		(instances
			(project "artix-dc-scm"
				(path ""
					(reference "C98")
					(unit 1)
				)
			)
		)
	)
	(symbol
		(lib_id "antmicroCapacitors0603:C_4u7_0603")
		(at 137.16 55.88 270)
		(mirror x)
		(unit 1)
		(exclude_from_sim no)
		(in_bom yes)
		(on_board yes)
		(dnp no)
		(property "Reference" "C106"
			(at 136.525 51.435 90)
			(effects
				(font
					(size 1.27 1.27)
				)
				(justify right)
			)
		)
		(property "Value" "C_4u7_0603"
			(at 127 35.56 0)
			(effects
				(font
					(size 1.27 1.27)
					(thickness 0.15)
				)
				(justify left bottom)
				(hide yes)
			)
		)
		(property "Footprint" "antmicro-footprints:C_0603_1608Metric"
			(at 124.46 35.56 0)
			(effects
				(font
					(size 1.27 1.27)
					(thickness 0.15)
				)
				(justify left bottom)
				(hide yes)
			)
		)
		(property "Datasheet" "https://product.tdk.com/en/search/capacitor/ceramic/mlcc/info?part_no=C1608X5R1V475M080AC"
			(at 121.92 35.56 0)
			(effects
				(font
					(size 1.27 1.27)
					(thickness 0.15)
				)
				(justify left bottom)
				(hide yes)
			)
		)
		(property "Description" "SMD Multilayer Ceramic Capacitor, 4.7 µF, 35 V, 0603 [1608 Metric], ± 20%, X5R, C"
			(at 137.16 55.88 0)
			(effects
				(font
					(size 1.27 1.27)
				)
				(hide yes)
			)
		)
		(property "Manufacturer" "TDK"
			(at 116.84 35.56 0)
			(effects
				(font
					(size 1.27 1.27)
					(thickness 0.15)
				)
				(justify left bottom)
				(hide yes)
			)
		)
		(property "MPN" "C1608X5R1V475M080AC"
			(at 119.38 35.56 0)
			(effects
				(font
					(size 1.27 1.27)
					(thickness 0.15)
				)
				(justify left bottom)
				(hide yes)
			)
		)
		(property "Val" "4u7"
			(at 136.525 55.245 90)
			(effects
				(font
					(size 1.27 1.27)
					(thickness 0.15)
				)
				(justify right)
			)
		)
		(property "License" "Apache-2.0"
			(at 114.3 35.56 0)
			(effects
				(font
					(size 1.27 1.27)
					(thickness 0.15)
				)
				(justify left bottom)
				(hide yes)
			)
		)
		(property "Author" "Antmicro"
			(at 111.76 35.56 0)
			(effects
				(font
					(size 1.27 1.27)
					(thickness 0.15)
				)
				(justify left bottom)
				(hide yes)
			)
		)
		(property "Voltage" ""
			(at 109.22 35.56 0)
			(effects
				(font
					(size 1.27 1.27)
				)
				(justify left bottom)
				(hide yes)
			)
		)
		(property "Dielectric" ""
			(at 106.68 35.56 0)
			(effects
				(font
					(size 1.27 1.27)
				)
				(justify left bottom)
				(hide yes)
			)
		)
		(property "DNP" ""
			(at 137.16 55.88 0)
			(effects
				(font
					(size 1.27 1.27)
				)
			)
		)
		(pin "1"
		)
		(pin "2"
		)
		(instances
			(project "artix-dc-scm"
				(path ""
					(reference "C106")
					(unit 1)
				)
			)
		)
	)
	(symbol
		(lib_id "antmicroCapacitors0402:C_470n_0402")
		(at 332.74 55.88 270)
		(mirror x)
		(unit 1)
		(exclude_from_sim no)
		(in_bom yes)
		(on_board yes)
		(dnp no)
		(property "Reference" "C110"
			(at 332.105 51.435 90)
			(effects
				(font
					(size 1.27 1.27)
				)
				(justify right)
			)
		)
		(property "Value" "C_470n_0402"
			(at 322.58 35.56 0)
			(effects
				(font
					(size 1.27 1.27)
					(thickness 0.15)
				)
				(justify left bottom)
				(hide yes)
			)
		)
		(property "Footprint" "antmicro-footprints:C_0402_1005Metric"
			(at 320.04 35.56 0)
			(effects
				(font
					(size 1.27 1.27)
					(thickness 0.15)
				)
				(justify left bottom)
				(hide yes)
			)
		)
		(property "Datasheet" "https://product.tdk.com/en/search/capacitor/ceramic/mlcc/info?part_no=C1005X5R1E474M050BB"
			(at 317.5 35.56 0)
			(effects
				(font
					(size 1.27 1.27)
					(thickness 0.15)
				)
				(justify left bottom)
				(hide yes)
			)
		)
		(property "Description" "SMD Multilayer Ceramic Capacitor, 0.47 µF, 25 V, 0402 [1005 Metric], ± 20%, X5R, C"
			(at 332.74 55.88 0)
			(effects
				(font
					(size 1.27 1.27)
				)
				(hide yes)
			)
		)
		(property "Manufacturer" "TDK"
			(at 312.42 35.56 0)
			(effects
				(font
					(size 1.27 1.27)
					(thickness 0.15)
				)
				(justify left bottom)
				(hide yes)
			)
		)
		(property "MPN" "C1005X5R1E474M050BB"
			(at 314.96 35.56 0)
			(effects
				(font
					(size 1.27 1.27)
					(thickness 0.15)
				)
				(justify left bottom)
				(hide yes)
			)
		)
		(property "Val" "470n"
			(at 332.105 55.245 90)
			(effects
				(font
					(size 1.27 1.27)
					(thickness 0.15)
				)
				(justify right)
			)
		)
		(property "License" "Apache-2.0"
			(at 309.88 35.56 0)
			(effects
				(font
					(size 1.27 1.27)
					(thickness 0.15)
				)
				(justify left bottom)
				(hide yes)
			)
		)
		(property "Author" "Antmicro"
			(at 307.34 35.56 0)
			(effects
				(font
					(size 1.27 1.27)
					(thickness 0.15)
				)
				(justify left bottom)
				(hide yes)
			)
		)
		(property "Voltage" ""
			(at 304.8 35.56 0)
			(effects
				(font
					(size 1.27 1.27)
				)
				(justify left bottom)
				(hide yes)
			)
		)
		(property "Dielectric" ""
			(at 302.26 35.56 0)
			(effects
				(font
					(size 1.27 1.27)
				)
				(justify left bottom)
				(hide yes)
			)
		)
		(property "DNP" ""
			(at 332.74 55.88 0)
			(effects
				(font
					(size 1.27 1.27)
				)
			)
		)
		(pin "1"
		)
		(pin "2"
		)
		(instances
			(project "artix-dc-scm"
				(path ""
					(reference "C110")
					(unit 1)
				)
			)
		)
	)
	(symbol
		(lib_id "antmicroCapacitors0402:C_470n_0402")
		(at 236.22 71.12 90)
		(unit 1)
		(exclude_from_sim no)
		(in_bom yes)
		(on_board yes)
		(dnp no)
		(property "Reference" "C234"
			(at 236.855 66.675 90)
			(effects
				(font
					(size 1.27 1.27)
				)
				(justify right)
			)
		)
		(property "Value" "C_470n_0402"
			(at 246.38 50.8 0)
			(effects
				(font
					(size 1.27 1.27)
					(thickness 0.15)
				)
				(justify left bottom)
				(hide yes)
			)
		)
		(property "Footprint" "antmicro-footprints:C_0402_1005Metric"
			(at 248.92 50.8 0)
			(effects
				(font
					(size 1.27 1.27)
					(thickness 0.15)
				)
				(justify left bottom)
				(hide yes)
			)
		)
		(property "Datasheet" "https://product.tdk.com/en/search/capacitor/ceramic/mlcc/info?part_no=C1005X5R1E474M050BB"
			(at 251.46 50.8 0)
			(effects
				(font
					(size 1.27 1.27)
					(thickness 0.15)
				)
				(justify left bottom)
				(hide yes)
			)
		)
		(property "Description" "SMD Multilayer Ceramic Capacitor, 0.47 µF, 25 V, 0402 [1005 Metric], ± 20%, X5R, C"
			(at 236.22 71.12 0)
			(effects
				(font
					(size 1.27 1.27)
				)
				(hide yes)
			)
		)
		(property "Manufacturer" "TDK"
			(at 256.54 50.8 0)
			(effects
				(font
					(size 1.27 1.27)
					(thickness 0.15)
				)
				(justify left bottom)
				(hide yes)
			)
		)
		(property "MPN" "C1005X5R1E474M050BB"
			(at 254 50.8 0)
			(effects
				(font
					(size 1.27 1.27)
					(thickness 0.15)
				)
				(justify left bottom)
				(hide yes)
			)
		)
		(property "Val" "470n"
			(at 236.855 70.485 90)
			(effects
				(font
					(size 1.27 1.27)
					(thickness 0.15)
				)
				(justify right)
			)
		)
		(property "License" "Apache-2.0"
			(at 259.08 50.8 0)
			(effects
				(font
					(size 1.27 1.27)
					(thickness 0.15)
				)
				(justify left bottom)
				(hide yes)
			)
		)
		(property "Author" "Antmicro"
			(at 261.62 50.8 0)
			(effects
				(font
					(size 1.27 1.27)
					(thickness 0.15)
				)
				(justify left bottom)
				(hide yes)
			)
		)
		(property "Voltage" ""
			(at 264.16 50.8 0)
			(effects
				(font
					(size 1.27 1.27)
				)
				(justify left bottom)
				(hide yes)
			)
		)
		(property "Dielectric" ""
			(at 266.7 50.8 0)
			(effects
				(font
					(size 1.27 1.27)
				)
				(justify left bottom)
				(hide yes)
			)
		)
		(pin "1"
		)
		(pin "2"
		)
		(instances
			(project "artix-dc-scm"
				(path ""
					(reference "C234")
					(unit 1)
				)
			)
		)
	)
	(symbol
		(lib_id "antmicropower:GND")
		(at 359.41 55.88 0)
		(mirror y)
		(unit 1)
		(exclude_from_sim no)
		(in_bom yes)
		(on_board yes)
		(dnp no)
		(property "Reference" "#PWR015"
			(at 359.41 62.23 0)
			(effects
				(font
					(size 1.27 1.27)
				)
				(hide yes)
			)
		)
		(property "Value" "GND"
			(at 359.41 59.69 0)
			(effects
				(font
					(size 1.27 1.27)
				)
			)
		)
		(property "Footprint" ""
			(at 359.41 55.88 0)
			(effects
				(font
					(size 1.27 1.27)
				)
				(hide yes)
			)
		)
		(property "Datasheet" ""
			(at 359.41 55.88 0)
			(effects
				(font
					(size 1.27 1.27)
				)
				(hide yes)
			)
		)
		(property "Description" ""
			(at 359.41 55.88 0)
			(effects
				(font
					(size 1.27 1.27)
				)
				(hide yes)
			)
		)
		(property "Author" "Antmicro"
			(at 350.52 63.5 0)
			(effects
				(font
					(size 1.27 1.27)
					(thickness 0.15)
				)
				(justify left bottom)
				(hide yes)
			)
		)
		(property "License" "Apache-2.0"
			(at 350.52 66.04 0)
			(effects
				(font
					(size 1.27 1.27)
					(thickness 0.15)
				)
				(justify left bottom)
				(hide yes)
			)
		)
		(pin "1"
		)
		(instances
			(project "artix-dc-scm"
				(path ""
					(reference "#PWR015")
					(unit 1)
				)
			)
		)
	)
)
